G04 ================== begin FILE IDENTIFICATION RECORD ==================*
G04 Layout Name:  DA0T6MTH8C0_t6m_tray_bp_c_brd_103112_274.brd*
G04 Film Name:    ssb.art*
G04 File Format:  Gerber RS274X*
G04 File Origin:  Cadence Allegro 16.3-S048*
G04 Origin Date:  Tue Nov 26 11:26:41 2013*
G04 *
G04 Layer:  BOARD GEOMETRY/OUTLINE*
G04 Layer:  DRAWING FORMAT/TITLE_BLOCK*
G04 Layer:  MANUFACTURING/TP_TEXT_BOTTOM*
G04 Layer:  REF DES/SILKSCREEN_BOTTOM*
G04 Layer:  PACKAGE GEOMETRY/SILKSCREEN_BOTTOM*
G04 Layer:  MANUFACTURING/PHOTOPLOT_OUTLINE*
G04 Layer:  DRAWING FORMAT/TITLE_DATA_SSB*
G04 Layer:  BOARD GEOMETRY/SILKSCREEN_BOTTOM*
G04 *
G04 Offset:    (0.00 0.00)*
G04 Mirror:    No*
G04 Mode:      Positive*
G04 Rotation:  0*
G04 FullContactRelief:  No*
G04 UndefLineWidth:     6.00*
G04 ================== end FILE IDENTIFICATION RECORD ====================*
%FSLAX25Y25*MOIN*%
%IR0*IPPOS*OFA0.00000B0.00000*MIA0B0*SFA1.00000B1.00000*%
%ADD10C,.006*%
G75*
%LPD*%
G75*
G54D10*
G01X1683504Y165354D02*
Y190512D01*
G03X1675630Y198386I-7874J0D01*
G01X1503898D01*
X1502406Y198679D01*
X1501137Y199516D01*
X1500279Y200772D01*
X1499930Y202268D01*
X1499661Y203554D01*
X1498808Y204831D01*
X1497530Y205685D01*
X1496024Y205984D01*
X1468465D01*
G03X1464528Y202047I0J-3937D01*
G01Y200000D01*
G02X1460591Y196063I-3937J0D01*
G01X1401535D01*
G02X1397598Y200000I0J3937D01*
G01Y202047D01*
G03X1393661Y205984I-3937J0D01*
G01X1319173D01*
G03X1315236Y202047I0J-3937D01*
G01Y200000D01*
G02X1311299Y196063I-3937J0D01*
G01X1252244D01*
G02X1248307Y200000I0J3937D01*
G01Y202047D01*
G03X1244370Y205984I-3937J0D01*
G01X807047D01*
X805541Y205685D01*
X804263Y204831D01*
X803410Y203554D01*
X803141Y202268D01*
X802792Y200772D01*
X801934Y199516D01*
X800665Y198679D01*
X799173Y198386D01*
X633819D01*
X632327Y198679D01*
X631058Y199516D01*
X630200Y200772D01*
X629851Y202268D01*
X629582Y203554D01*
X628729Y204831D01*
X627451Y205685D01*
X625945Y205984D01*
X598386D01*
G03X594449Y202047I0J-3937D01*
G01Y200000D01*
G02X590512Y196063I-3937J0D01*
G01X531457D01*
G02X527520Y200000I0J3937D01*
G01Y202047D01*
G03X523583Y205984I-3937J0D01*
G01X449094D01*
G03X445157Y202047I0J-3937D01*
G01Y200000D01*
G02X441220Y196063I-3937J0D01*
G01X382165D01*
G02X378228Y200000I0J3937D01*
G01Y202047D01*
G03X374291Y205984I-3937J0D01*
G01X228661D01*
G03X220787Y198110I0J-7874D01*
G01Y170551D01*
G02X216850Y166614I-3937J0D01*
G01X208976D01*
G02X205039Y170551I0J3937D01*
G01Y203937D01*
X199134Y209842D01*
X49803D01*
X43898Y203937D01*
Y167913D01*
G02X41142I-1378J0D01*
G01Y203937D01*
X37205Y207874D01*
X35236Y209842D01*
X5906D01*
X3937Y207874D01*
X0Y203937D01*
Y7874D01*
G03X7874Y0I7874J0D01*
G01X1680354D01*
G03X1688228Y7874I0J7874D01*
G01Y39370D01*
G03X1686260Y41339I-1969J0D01*
G01X1685472D01*
G02X1683504Y43307I0J1968D01*
G01Y122047D01*
G03X1681535Y124016I-1969J0D01*
G01X1675236D01*
G02X1673268Y125984I0J1968D01*
G01Y161417D01*
G02X1675236Y163386I1968J1D01*
G01X1681535D01*
G03X1683504Y165354I1J1968D01*
G01X10433Y114173D02*
Y128497D01*
G02X25000I7283J9298D01*
G01Y114173D01*
G02X10433I-7284J0D01*
G01X306929Y163386D02*
Y177710D01*
G02X321496I7283J9298D01*
G01Y163386D01*
G02X306929I-7283J0D01*
G01X457212Y-338900D02*
Y-343900D01*
G01X455755Y-338900D02*
X458669D01*
G01X463579Y-343900D02*
X461045D01*
Y-338900D01*
X463579D01*
G01X462565Y-341317D02*
X461045D01*
G01X466145Y-338900D02*
Y-343900D01*
X468679D01*
G01X472512Y-344067D02*
X472385Y-343983D01*
Y-343817D01*
X472512Y-343733D01*
X472639Y-343817D01*
Y-343983D01*
X472512Y-344067D01*
G01Y-341817D02*
X472385Y-341733D01*
Y-341567D01*
X472512Y-341483D01*
X472639Y-341567D01*
Y-341733D01*
X472512Y-341817D01*
G01X477295Y-345567D02*
X476662Y-344733D01*
X476345Y-343900D01*
Y-340567D01*
X476662Y-339733D01*
X477295Y-338900D01*
G01X482712D02*
X482205Y-339067D01*
X481825Y-339483D01*
X481572Y-339983D01*
X481382Y-340650D01*
X481319Y-341400D01*
X481382Y-342150D01*
X481572Y-342817D01*
X481825Y-343317D01*
X482205Y-343733D01*
X482712Y-343900D01*
X483219Y-343733D01*
X483599Y-343317D01*
X483852Y-342817D01*
X484042Y-342150D01*
X484105Y-341400D01*
X484042Y-340650D01*
X483852Y-339983D01*
X483599Y-339483D01*
X483219Y-339067D01*
X482712Y-338900D01*
G01X486419Y-342900D02*
X486799Y-343483D01*
X487305Y-343817D01*
X487875Y-343900D01*
X488382Y-343817D01*
X488889Y-343400D01*
X489205Y-342900D01*
X489269Y-342400D01*
X489142Y-341817D01*
X488699Y-341400D01*
X488255Y-341233D01*
X487685D01*
G01X488255D02*
X488635Y-340983D01*
X488952Y-340567D01*
X489079Y-340067D01*
X488952Y-339567D01*
X488635Y-339150D01*
X488065Y-338900D01*
X487495Y-338983D01*
X486925Y-339317D01*
G01X493229Y-345567D02*
X493862Y-344733D01*
X494179Y-343900D01*
Y-340567D01*
X493862Y-339733D01*
X493229Y-338900D01*
G01X496619Y-342900D02*
X496999Y-343483D01*
X497505Y-343817D01*
X498075Y-343900D01*
X498582Y-343817D01*
X499089Y-343400D01*
X499405Y-342900D01*
X499469Y-342400D01*
X499342Y-341817D01*
X498899Y-341400D01*
X498455Y-341233D01*
X497885D01*
G01X498455D02*
X498835Y-340983D01*
X499152Y-340567D01*
X499279Y-340067D01*
X499152Y-339567D01*
X498835Y-339150D01*
X498265Y-338900D01*
X497695Y-338983D01*
X497125Y-339317D01*
G01X501909Y-339733D02*
X502289Y-339233D01*
X502732Y-338983D01*
X503239Y-338900D01*
X503872Y-339067D01*
X504315Y-339483D01*
X504442Y-339983D01*
X504379Y-340483D01*
X504125Y-340900D01*
X502859Y-341733D01*
X502289Y-342317D01*
X501909Y-343150D01*
X501782Y-343900D01*
X504442D01*
G01X508085D02*
X508212Y-342817D01*
X508402Y-341900D01*
X508655Y-341067D01*
X508972Y-340150D01*
X509479Y-338900D01*
X506945D01*
G01X512489Y-342233D02*
X514135D01*
G01X517209Y-339733D02*
X517589Y-339233D01*
X518032Y-338983D01*
X518539Y-338900D01*
X519172Y-339067D01*
X519615Y-339483D01*
X519742Y-339983D01*
X519679Y-340483D01*
X519425Y-340900D01*
X518159Y-341733D01*
X517589Y-342317D01*
X517209Y-343150D01*
X517082Y-343900D01*
X519742D01*
G01X522119Y-342900D02*
X522499Y-343483D01*
X523005Y-343817D01*
X523575Y-343900D01*
X524082Y-343817D01*
X524589Y-343400D01*
X524905Y-342900D01*
X524969Y-342400D01*
X524842Y-341817D01*
X524399Y-341400D01*
X523955Y-341233D01*
X523385D01*
G01X523955D02*
X524335Y-340983D01*
X524652Y-340567D01*
X524779Y-340067D01*
X524652Y-339567D01*
X524335Y-339150D01*
X523765Y-338900D01*
X523195Y-338983D01*
X522625Y-339317D01*
G01X529372Y-343900D02*
Y-338900D01*
X527029Y-342483D01*
X530195D01*
G01X532319Y-343150D02*
X532699Y-343567D01*
X533142Y-343817D01*
X533712Y-343900D01*
X534282Y-343733D01*
X534725Y-343400D01*
X535042Y-342817D01*
X535105Y-342150D01*
X534979Y-341483D01*
X534662Y-341067D01*
X534219Y-340733D01*
X533775Y-340650D01*
X533332Y-340733D01*
X532762Y-341067D01*
X532952Y-338900D01*
X534662D01*
G01X542709Y-343900D02*
Y-338900D01*
X545115D01*
G01X544229Y-341317D02*
X542709D01*
G01X547429Y-343900D02*
X549012Y-338900D01*
X550595Y-343900D01*
G01X550025Y-342150D02*
X547999D01*
G01X552782Y-343900D02*
X555442Y-338900D01*
G01X552782D02*
X555442Y-343900D01*
G01X559212Y-344067D02*
X559085Y-343983D01*
Y-343817D01*
X559212Y-343733D01*
X559339Y-343817D01*
Y-343983D01*
X559212Y-344067D01*
G01Y-341817D02*
X559085Y-341733D01*
Y-341567D01*
X559212Y-341483D01*
X559339Y-341567D01*
Y-341733D01*
X559212Y-341817D01*
G01X563995Y-345567D02*
X563362Y-344733D01*
X563045Y-343900D01*
Y-340567D01*
X563362Y-339733D01*
X563995Y-338900D01*
G01X569412D02*
X568905Y-339067D01*
X568525Y-339483D01*
X568272Y-339983D01*
X568082Y-340650D01*
X568019Y-341400D01*
X568082Y-342150D01*
X568272Y-342817D01*
X568525Y-343317D01*
X568905Y-343733D01*
X569412Y-343900D01*
X569919Y-343733D01*
X570299Y-343317D01*
X570552Y-342817D01*
X570742Y-342150D01*
X570805Y-341400D01*
X570742Y-340650D01*
X570552Y-339983D01*
X570299Y-339483D01*
X569919Y-339067D01*
X569412Y-338900D01*
G01X573119Y-342900D02*
X573499Y-343483D01*
X574005Y-343817D01*
X574575Y-343900D01*
X575082Y-343817D01*
X575589Y-343400D01*
X575905Y-342900D01*
X575969Y-342400D01*
X575842Y-341817D01*
X575399Y-341400D01*
X574955Y-341233D01*
X574385D01*
G01X574955D02*
X575335Y-340983D01*
X575652Y-340567D01*
X575779Y-340067D01*
X575652Y-339567D01*
X575335Y-339150D01*
X574765Y-338900D01*
X574195Y-338983D01*
X573625Y-339317D01*
G01X579929Y-345567D02*
X580562Y-344733D01*
X580879Y-343900D01*
Y-340567D01*
X580562Y-339733D01*
X579929Y-338900D01*
G01X583319Y-342900D02*
X583699Y-343483D01*
X584205Y-343817D01*
X584775Y-343900D01*
X585282Y-343817D01*
X585789Y-343400D01*
X586105Y-342900D01*
X586169Y-342400D01*
X586042Y-341817D01*
X585599Y-341400D01*
X585155Y-341233D01*
X584585D01*
G01X585155D02*
X585535Y-340983D01*
X585852Y-340567D01*
X585979Y-340067D01*
X585852Y-339567D01*
X585535Y-339150D01*
X584965Y-338900D01*
X584395Y-338983D01*
X583825Y-339317D01*
G01X588735Y-343317D02*
X589179Y-343733D01*
X589685Y-343900D01*
X590192Y-343733D01*
X590635Y-343233D01*
X590952Y-342483D01*
X591079Y-341733D01*
Y-340817D01*
X590952Y-340067D01*
X590635Y-339400D01*
X590255Y-339067D01*
X589812Y-338900D01*
X589305Y-339067D01*
X588925Y-339400D01*
X588672Y-339900D01*
X588545Y-340567D01*
X588672Y-341150D01*
X588989Y-341733D01*
X589369Y-342067D01*
X589812Y-342150D01*
X590319Y-341983D01*
X590699Y-341567D01*
X591079Y-340817D01*
G01X594785Y-343900D02*
X594912Y-342817D01*
X595102Y-341900D01*
X595355Y-341067D01*
X595672Y-340150D01*
X596179Y-338900D01*
X593645D01*
G01X599189Y-342233D02*
X600835D01*
G01X603719Y-342900D02*
X604099Y-343483D01*
X604605Y-343817D01*
X605175Y-343900D01*
X605682Y-343817D01*
X606189Y-343400D01*
X606505Y-342900D01*
X606569Y-342400D01*
X606442Y-341817D01*
X605999Y-341400D01*
X605555Y-341233D01*
X604985D01*
G01X605555D02*
X605935Y-340983D01*
X606252Y-340567D01*
X606379Y-340067D01*
X606252Y-339567D01*
X605935Y-339150D01*
X605365Y-338900D01*
X604795Y-338983D01*
X604225Y-339317D01*
G01X609009Y-341817D02*
X609452Y-341233D01*
X609832Y-340900D01*
X610339Y-340733D01*
X610782Y-340900D01*
X611099Y-341233D01*
X611352Y-341733D01*
X611415Y-342317D01*
X611352Y-342817D01*
X611099Y-343317D01*
X610719Y-343733D01*
X610275Y-343900D01*
X609769Y-343733D01*
X609325Y-343233D01*
X609072Y-342483D01*
X609009Y-341650D01*
X609135Y-340567D01*
X609325Y-339983D01*
X609642Y-339400D01*
X610085Y-338983D01*
X610529Y-338900D01*
X610972Y-339067D01*
X611289Y-339483D01*
G01X615312Y-343900D02*
Y-338900D01*
X614552Y-339900D01*
G01Y-343900D02*
X616072D01*
G01X621172D02*
Y-338900D01*
X618829Y-342483D01*
X621995D01*
G01X445212Y-273900D02*
Y-348900D01*
X945212D01*
Y-273900D01*
X445212D01*
G01X465926Y1809D02*
X466194Y1448D01*
X466424Y1241D01*
X466731Y1138D01*
X466999Y1241D01*
X467191Y1448D01*
X467344Y1758D01*
X467382Y2119D01*
X467344Y2429D01*
X467191Y2739D01*
X466961Y2998D01*
X466692Y3101D01*
X466386Y2998D01*
X466117Y2688D01*
X465964Y2223D01*
X465926Y1706D01*
X466002Y1034D01*
X466117Y673D01*
X466309Y311D01*
X466577Y53D01*
X466846Y1D01*
X467114Y104D01*
X467306Y363D01*
G01X483314Y3301D02*
Y201D01*
X481896Y2423D01*
X483812D01*
G01X473811Y2836D02*
X474041Y3094D01*
X474309Y3249D01*
X474654Y3301D01*
X474999Y3198D01*
X475267Y2991D01*
X475459Y2629D01*
X475497Y2216D01*
X475421Y1803D01*
X475229Y1544D01*
X474961Y1338D01*
X474692Y1286D01*
X474424Y1338D01*
X474079Y1544D01*
X474194Y201D01*
X475229D01*
G01X489811Y2681D02*
X490041Y3043D01*
X490347Y3249D01*
X490692Y3301D01*
X490999Y3249D01*
X491306Y2991D01*
X491497Y2681D01*
X491536Y2371D01*
X491459Y2009D01*
X491191Y1751D01*
X490922Y1648D01*
X490577D01*
G01X490922D02*
X491152Y1493D01*
X491344Y1234D01*
X491421Y924D01*
X491344Y614D01*
X491152Y356D01*
X490807Y201D01*
X490462Y253D01*
X490117Y459D01*
G01X506054Y3301D02*
Y201D01*
X505594Y821D01*
G01Y3301D02*
X506514D01*
G01X497526Y718D02*
X497756Y408D01*
X498024Y253D01*
X498331Y201D01*
X498714Y304D01*
X498982Y563D01*
X499059Y873D01*
X499021Y1183D01*
X498867Y1441D01*
X498101Y1958D01*
X497756Y2319D01*
X497526Y2836D01*
X497449Y3301D01*
X499059D01*
G01X640212Y-273900D02*
Y-348900D01*
G01Y-323900D02*
X743212D01*
Y-298900D01*
G01X640212D02*
X743212D01*
G01Y-273900D02*
Y-348900D01*
G01X745212Y-273900D02*
Y-348900D01*
G01X750719Y-333900D02*
Y-328900D01*
X751985D01*
X752492Y-329150D01*
X752872Y-329483D01*
X753189Y-329983D01*
X753442Y-330567D01*
X753505Y-331400D01*
X753442Y-332233D01*
X753189Y-332817D01*
X752872Y-333317D01*
X752492Y-333650D01*
X751985Y-333900D01*
X750719D01*
G01X755629D02*
X757212Y-328900D01*
X758795Y-333900D01*
G01X758225Y-332150D02*
X756199D01*
G01X762312Y-328900D02*
Y-333900D01*
G01X760855Y-328900D02*
X763769D01*
G01X768679Y-333900D02*
X766145D01*
Y-328900D01*
X768679D01*
G01X767665Y-331317D02*
X766145D01*
G01X772512Y-334067D02*
X772385Y-333983D01*
Y-333817D01*
X772512Y-333733D01*
X772639Y-333817D01*
Y-333983D01*
X772512Y-334067D01*
G01Y-331817D02*
X772385Y-331733D01*
Y-331567D01*
X772512Y-331483D01*
X772639Y-331567D01*
Y-331733D01*
X772512Y-331817D01*
G01X745212Y-323900D02*
X945212D01*
G01X750845Y-308900D02*
Y-303900D01*
X752365D01*
X752872Y-304150D01*
X753252Y-304733D01*
X753379Y-305400D01*
X753252Y-306067D01*
X752935Y-306567D01*
X752365Y-306817D01*
X750845D01*
G01X756072Y-309067D02*
X758352Y-303900D01*
G01X760855Y-308900D02*
Y-303900D01*
X763769Y-308900D01*
Y-303900D01*
G01X767412Y-309067D02*
X767285Y-308983D01*
Y-308817D01*
X767412Y-308733D01*
X767539Y-308817D01*
Y-308983D01*
X767412Y-309067D01*
G01Y-306817D02*
X767285Y-306733D01*
Y-306567D01*
X767412Y-306483D01*
X767539Y-306567D01*
Y-306733D01*
X767412Y-306817D01*
G01X745212Y-298900D02*
X945212D01*
G01X750845Y-283900D02*
Y-278900D01*
X752365D01*
X752872Y-279150D01*
X753252Y-279733D01*
X753379Y-280400D01*
X753252Y-281067D01*
X752935Y-281567D01*
X752365Y-281817D01*
X750845D01*
G01X755945Y-283900D02*
Y-278900D01*
X757529D01*
X758035Y-279150D01*
X758352Y-279483D01*
X758479Y-280150D01*
X758352Y-280817D01*
X757972Y-281233D01*
X757529Y-281483D01*
X755945D01*
G01X757529D02*
X758479Y-283900D01*
G01X762312D02*
X761805Y-283817D01*
X761362Y-283483D01*
X760982Y-282983D01*
X760729Y-282400D01*
X760602Y-281733D01*
Y-281067D01*
X760729Y-280400D01*
X760982Y-279817D01*
X761362Y-279317D01*
X761805Y-278983D01*
X762312Y-278900D01*
X762819Y-278983D01*
X763262Y-279317D01*
X763642Y-279817D01*
X763895Y-280400D01*
X764022Y-281067D01*
Y-281733D01*
X763895Y-282400D01*
X763642Y-282983D01*
X763262Y-283483D01*
X762819Y-283817D01*
X762312Y-283900D01*
G01X766145Y-282900D02*
X766462Y-283400D01*
X766842Y-283733D01*
X767285Y-283900D01*
X767792Y-283733D01*
X768172Y-283400D01*
X768552Y-282900D01*
X768679Y-282233D01*
Y-278900D01*
G01X773779Y-283900D02*
X771245D01*
Y-278900D01*
X773779D01*
G01X772765Y-281317D02*
X771245D01*
G01X779005Y-279317D02*
X778625Y-279067D01*
X778182Y-278900D01*
X777675D01*
X777105Y-279150D01*
X776662Y-279567D01*
X776345Y-280067D01*
X776092Y-280900D01*
X776029Y-281650D01*
X776155Y-282400D01*
X776345Y-282900D01*
X776725Y-283400D01*
X777169Y-283733D01*
X777612Y-283900D01*
X778055D01*
X778499Y-283733D01*
X778879Y-283483D01*
X779195Y-283150D01*
G01X782712Y-278900D02*
Y-283900D01*
G01X781255Y-278900D02*
X784169D01*
G01X787812Y-284067D02*
X787685Y-283983D01*
Y-283817D01*
X787812Y-283733D01*
X787939Y-283817D01*
Y-283983D01*
X787812Y-284067D01*
G01Y-281817D02*
X787685Y-281733D01*
Y-281567D01*
X787812Y-281483D01*
X787939Y-281567D01*
Y-281733D01*
X787812Y-281817D01*
G01X776772Y18504D02*
Y32533D01*
G02X790551I6889J9593D01*
G01Y18504D01*
G02X776772I-6890J0D01*
G01X819134Y163386D02*
Y177415D01*
G02X832913I6890J9593D01*
G01Y163386D01*
G02X819134I-6889J0D01*
G01X860212Y-323900D02*
Y-348900D01*
G01X865845Y-333900D02*
Y-328900D01*
X867429D01*
X867935Y-329150D01*
X868252Y-329483D01*
X868379Y-330150D01*
X868252Y-330817D01*
X867872Y-331233D01*
X867429Y-331483D01*
X865845D01*
G01X867429D02*
X868379Y-333900D01*
G01X873479D02*
X870945D01*
Y-328900D01*
X873479D01*
G01X872465Y-331317D02*
X870945D01*
G01X875729Y-328900D02*
X877312Y-333900D01*
X878895Y-328900D01*
G01X882412Y-334067D02*
X882285Y-333983D01*
Y-333817D01*
X882412Y-333733D01*
X882539Y-333817D01*
Y-333983D01*
X882412Y-334067D01*
G01Y-331817D02*
X882285Y-331733D01*
Y-331567D01*
X882412Y-331483D01*
X882539Y-331567D01*
Y-331733D01*
X882412Y-331817D01*
G01X909212Y-323900D02*
Y-348900D01*
G01X1094331Y18504D02*
Y32828D01*
G02X1108898I7283J9298D01*
G01Y18504D01*
G02X1094331I-7283J0D01*
G01X1177008Y163386D02*
Y177710D01*
G02X1191575I7284J9298D01*
G01Y163386D01*
G02X1177008I-7283J0D01*
G01X1336005Y1809D02*
X1336273Y1448D01*
X1336503Y1241D01*
X1336810Y1138D01*
X1337078Y1241D01*
X1337270Y1448D01*
X1337423Y1758D01*
X1337461Y2119D01*
X1337423Y2429D01*
X1337270Y2739D01*
X1337040Y2998D01*
X1336771Y3101D01*
X1336465Y2998D01*
X1336196Y2688D01*
X1336043Y2223D01*
X1336005Y1706D01*
X1336081Y1034D01*
X1336196Y673D01*
X1336388Y311D01*
X1336656Y53D01*
X1336925Y1D01*
X1337193Y104D01*
X1337385Y363D01*
G01X1353393Y3301D02*
Y201D01*
X1351975Y2423D01*
X1353891D01*
G01X1343890Y2836D02*
X1344120Y3094D01*
X1344388Y3249D01*
X1344733Y3301D01*
X1345078Y3198D01*
X1345346Y2991D01*
X1345538Y2629D01*
X1345576Y2216D01*
X1345500Y1803D01*
X1345308Y1544D01*
X1345040Y1338D01*
X1344771Y1286D01*
X1344503Y1338D01*
X1344158Y1544D01*
X1344273Y201D01*
X1345308D01*
G01X1359890Y2681D02*
X1360120Y3043D01*
X1360426Y3249D01*
X1360771Y3301D01*
X1361078Y3249D01*
X1361385Y2991D01*
X1361576Y2681D01*
X1361615Y2371D01*
X1361538Y2009D01*
X1361270Y1751D01*
X1361001Y1648D01*
X1360656D01*
G01X1361001D02*
X1361231Y1493D01*
X1361423Y1234D01*
X1361500Y924D01*
X1361423Y614D01*
X1361231Y356D01*
X1360886Y201D01*
X1360541Y253D01*
X1360196Y459D01*
G01X1376133Y3301D02*
Y201D01*
X1375673Y821D01*
G01Y3301D02*
X1376593D01*
G01X1367605Y718D02*
X1367835Y408D01*
X1368103Y253D01*
X1368410Y201D01*
X1368793Y304D01*
X1369061Y563D01*
X1369138Y873D01*
X1369100Y1183D01*
X1368946Y1441D01*
X1368180Y1958D01*
X1367835Y2319D01*
X1367605Y2836D01*
X1367528Y3301D01*
X1369138D01*
G01X-471400Y-391900D02*
Y1528800D01*
X2244200D01*
Y-391900D01*
X-471400D01*
G01X-39383Y18504D02*
G03X-19542Y-24764I57100J1D01*
G01X-17908Y-26120D02*
G03X-39383Y18504I35633J44628D01*
G01X-13779D02*
G03X35919Y44208I31496J0D01*
G01X-485D02*
G03X-13779Y18504I18202J-25704D01*
G01X4190Y81325D02*
X3960Y81635D01*
X3692Y81790D01*
X3385Y81842D01*
X3002Y81739D01*
X2734Y81480D01*
X2657Y81170D01*
X2695Y80860D01*
X2849Y80602D01*
X3615Y80085D01*
X3960Y79724D01*
X4190Y79207D01*
X4267Y78742D01*
X2657D01*
G01X4290Y92625D02*
X4060Y92935D01*
X3792Y93090D01*
X3485Y93142D01*
X3102Y93039D01*
X2834Y92780D01*
X2757Y92470D01*
X2795Y92160D01*
X2949Y91902D01*
X3715Y91385D01*
X4060Y91024D01*
X4290Y90507D01*
X4367Y90042D01*
X2757D01*
G01X7536Y162728D02*
X7229Y162470D01*
X6884Y162315D01*
X6578D01*
X6271Y162470D01*
X6041Y162728D01*
X5926Y163090D01*
X6003Y163452D01*
X6194Y163762D01*
X6539Y163968D01*
X6999Y164072D01*
X7268Y164278D01*
X7383Y164640D01*
X7306Y165002D01*
X7114Y165260D01*
X6846Y165415D01*
X6578D01*
X6309Y165312D01*
X6079Y165053D01*
G01X3708Y162315D02*
X3631Y162987D01*
X3516Y163555D01*
X3363Y164072D01*
X3171Y164640D01*
X2864Y165415D01*
X4398D01*
G01X40689Y167123D02*
X2757D01*
G01Y173229D02*
Y203938D01*
X8662Y209843D01*
X35237D01*
X41143Y203938D01*
Y167914D01*
G03X42521Y166536I1378J0D01*
G03X43898Y167914I-1J1378D01*
G01Y178295D01*
G01X24262Y78642D02*
Y81742D01*
X24722Y81122D01*
G01Y78642D02*
X23802D01*
G01X24562Y90242D02*
Y93342D01*
X25022Y92722D01*
G01Y90242D02*
X24102D01*
G01X49733Y36516D02*
X46633D01*
X47253Y36976D01*
G01X49733D02*
Y36056D01*
G01Y33416D02*
X49681Y33148D01*
X49526Y32841D01*
X49268Y32649D01*
X48906Y32573D01*
X48545Y32649D01*
X48235Y32879D01*
X48080Y33224D01*
Y33608D01*
X47976Y33838D01*
X47718Y34029D01*
X47356Y34106D01*
X46995Y33991D01*
X46736Y33723D01*
X46633Y33416D01*
X46736Y33109D01*
X46995Y32841D01*
X47356Y32726D01*
X47718Y32803D01*
X47976Y32994D01*
X48080Y33224D01*
Y33608D01*
X48235Y33953D01*
X48545Y34183D01*
X48906Y34259D01*
X49268Y34183D01*
X49526Y33991D01*
X49681Y33684D01*
X49733Y33416D01*
G01X45967Y143916D02*
X42867D01*
X43487Y144376D01*
G01X45967D02*
Y143456D01*
G01X45347Y141659D02*
X45709Y141429D01*
X45915Y141123D01*
X45967Y140778D01*
X45915Y140471D01*
X45657Y140164D01*
X45347Y139973D01*
X45037Y139934D01*
X44675Y140011D01*
X44417Y140279D01*
X44314Y140548D01*
Y140893D01*
G01Y140548D02*
X44159Y140318D01*
X43900Y140126D01*
X43590Y140049D01*
X43280Y140126D01*
X43022Y140318D01*
X42867Y140663D01*
X42919Y141008D01*
X43125Y141353D01*
G01X39431Y162928D02*
X39124Y162670D01*
X38779Y162515D01*
X38473D01*
X38166Y162670D01*
X37936Y162928D01*
X37821Y163290D01*
X37898Y163652D01*
X38089Y163962D01*
X38434Y164168D01*
X38894Y164272D01*
X39163Y164478D01*
X39278Y164840D01*
X39201Y165202D01*
X39009Y165460D01*
X38741Y165615D01*
X38473D01*
X38204Y165512D01*
X37974Y165253D01*
G01X35526Y162515D02*
Y165615D01*
X35986Y164995D01*
G01Y162515D02*
X35066D01*
G01X33154Y165098D02*
X32924Y165408D01*
X32656Y165563D01*
X32349Y165615D01*
X31966Y165512D01*
X31698Y165253D01*
X31621Y164943D01*
X31659Y164633D01*
X31813Y164375D01*
X32579Y163858D01*
X32924Y163497D01*
X33154Y162980D01*
X33231Y162515D01*
X31621D01*
G01X207796Y167123D02*
X44389D01*
G01X44648Y204688D02*
X49804Y209843D01*
X201891D01*
X207796Y203938D01*
Y173229D01*
G01X57005Y37101D02*
X57264Y36832D01*
X57367Y36526D01*
X57264Y36219D01*
X56954Y35951D01*
X56489Y35759D01*
X56024Y35682D01*
X55455D01*
X54990Y35759D01*
X54577Y35951D01*
X54370Y36181D01*
X54267Y36449D01*
X54370Y36756D01*
X54577Y36986D01*
X54887Y37139D01*
X55300Y37216D01*
X55662Y37139D01*
X56024Y36947D01*
X56230Y36717D01*
X56282Y36449D01*
X56179Y36142D01*
X55920Y35912D01*
X55455Y35682D01*
G01X57367Y142366D02*
X54267D01*
X54887Y142826D01*
G01X57367D02*
Y141906D01*
G01X61743Y160568D02*
Y163668D01*
X60823D01*
X60516Y163513D01*
X60286Y163151D01*
X60209Y162738D01*
X60286Y162325D01*
X60478Y162015D01*
X60823Y161860D01*
X61743D01*
G01X58719Y161033D02*
X58489Y160775D01*
X58221Y160620D01*
X57876Y160568D01*
X57531Y160671D01*
X57263Y160878D01*
X57071Y161240D01*
X57033Y161653D01*
X57109Y162066D01*
X57301Y162325D01*
X57569Y162531D01*
X57838Y162583D01*
X58106Y162531D01*
X58451Y162325D01*
X58336Y163668D01*
X57301D01*
G01X91136Y64092D02*
X88036D01*
X88656Y64552D01*
G01X91136D02*
Y63632D01*
G01X80529Y64570D02*
X80219Y64340D01*
X80064Y64072D01*
X80012Y63765D01*
X80115Y63382D01*
X80374Y63114D01*
X80684Y63037D01*
X80994Y63075D01*
X81252Y63229D01*
X81769Y63995D01*
X82130Y64340D01*
X82647Y64570D01*
X83112Y64647D01*
Y63037D01*
G01X83262Y116074D02*
X80162D01*
X80782Y116534D01*
G01X83262D02*
Y115614D01*
G01X80679Y113702D02*
X80369Y113472D01*
X80214Y113204D01*
X80162Y112897D01*
X80265Y112514D01*
X80524Y112246D01*
X80834Y112169D01*
X81144Y112207D01*
X81402Y112361D01*
X81919Y113127D01*
X82280Y113472D01*
X82797Y113702D01*
X83262Y113779D01*
Y112169D01*
G01X91586Y115224D02*
X88486D01*
X89106Y115684D01*
G01X91586D02*
Y114764D01*
G01Y112124D02*
X88486D01*
X89106Y112584D01*
G01X91586D02*
Y111664D01*
G01X104190Y92725D02*
X103960Y93035D01*
X103692Y93190D01*
X103385Y93242D01*
X103002Y93139D01*
X102734Y92880D01*
X102657Y92570D01*
X102695Y92260D01*
X102849Y92002D01*
X103615Y91485D01*
X103960Y91124D01*
X104190Y90607D01*
X104267Y90142D01*
X102657D01*
G01X104590Y104825D02*
X104360Y105135D01*
X104092Y105290D01*
X103785Y105342D01*
X103402Y105239D01*
X103134Y104980D01*
X103057Y104670D01*
X103095Y104360D01*
X103249Y104102D01*
X104015Y103585D01*
X104360Y103224D01*
X104590Y102707D01*
X104667Y102242D01*
X103057D01*
G01X124262Y90542D02*
Y93642D01*
X124722Y93022D01*
G01Y90542D02*
X123802D01*
G01X124862Y102342D02*
Y105442D01*
X125322Y104822D01*
G01Y102342D02*
X124402D01*
G01X189076Y158972D02*
Y162072D01*
X188156D01*
X187849Y161917D01*
X187619Y161555D01*
X187542Y161142D01*
X187619Y160729D01*
X187811Y160419D01*
X188156Y160264D01*
X189076D01*
G01X185209Y158972D02*
X184941Y159024D01*
X184634Y159179D01*
X184442Y159437D01*
X184366Y159799D01*
X184442Y160160D01*
X184672Y160470D01*
X185017Y160625D01*
X185401D01*
X185631Y160729D01*
X185822Y160987D01*
X185899Y161349D01*
X185784Y161710D01*
X185516Y161969D01*
X185209Y162072D01*
X184902Y161969D01*
X184634Y161710D01*
X184519Y161349D01*
X184596Y160987D01*
X184787Y160729D01*
X185017Y160625D01*
X185401D01*
X185746Y160470D01*
X185976Y160160D01*
X186052Y159799D01*
X185976Y159437D01*
X185784Y159179D01*
X185477Y159024D01*
X185209Y158972D01*
G01X294022Y40283D02*
Y43383D01*
X294482Y42763D01*
G01Y40283D02*
X293562D01*
G01X386792Y-52954D02*
X316516D01*
G01D02*
Y86022D01*
G01X332047Y18651D02*
Y21751D01*
X331281D01*
X330974Y21596D01*
X330744Y21389D01*
X330552Y21079D01*
X330399Y20718D01*
X330361Y20201D01*
X330399Y19684D01*
X330552Y19323D01*
X330744Y19013D01*
X330974Y18806D01*
X331281Y18651D01*
X332047D01*
G01X328832Y21234D02*
X328602Y21544D01*
X328334Y21699D01*
X328027Y21751D01*
X327644Y21648D01*
X327376Y21389D01*
X327299Y21079D01*
X327337Y20769D01*
X327491Y20511D01*
X328257Y19994D01*
X328602Y19633D01*
X328832Y19116D01*
X328909Y18651D01*
X327299D01*
G01X332047Y10776D02*
Y13876D01*
X331281D01*
X330974Y13721D01*
X330744Y13514D01*
X330552Y13204D01*
X330399Y12843D01*
X330361Y12326D01*
X330399Y11809D01*
X330552Y11448D01*
X330744Y11138D01*
X330974Y10931D01*
X331281Y10776D01*
X332047D01*
G01X328947Y11396D02*
X328717Y11034D01*
X328411Y10828D01*
X328066Y10776D01*
X327759Y10828D01*
X327452Y11086D01*
X327261Y11396D01*
X327222Y11706D01*
X327299Y12068D01*
X327567Y12326D01*
X327836Y12429D01*
X328181D01*
G01X327836D02*
X327606Y12584D01*
X327414Y12843D01*
X327337Y13153D01*
X327414Y13463D01*
X327606Y13721D01*
X327951Y13876D01*
X328296Y13824D01*
X328641Y13618D01*
G01X332047Y26525D02*
Y29625D01*
X331281D01*
X330974Y29470D01*
X330744Y29263D01*
X330552Y28953D01*
X330399Y28592D01*
X330361Y28075D01*
X330399Y27558D01*
X330552Y27197D01*
X330744Y26887D01*
X330974Y26680D01*
X331281Y26525D01*
X332047D01*
G01X328104D02*
Y29625D01*
X328564Y29005D01*
G01Y26525D02*
X327644D01*
G01X332162Y42273D02*
X331204Y45373D01*
X330246Y42273D01*
G01X330591Y43358D02*
X331817D01*
G01X328947Y42893D02*
X328717Y42531D01*
X328411Y42325D01*
X328066Y42273D01*
X327759Y42325D01*
X327452Y42583D01*
X327261Y42893D01*
X327222Y43203D01*
X327299Y43565D01*
X327567Y43823D01*
X327836Y43926D01*
X328181D01*
G01X327836D02*
X327606Y44081D01*
X327414Y44340D01*
X327337Y44650D01*
X327414Y44960D01*
X327606Y45218D01*
X327951Y45373D01*
X328296Y45321D01*
X328641Y45115D01*
G01X332162Y50147D02*
X331204Y53247D01*
X330246Y50147D01*
G01X330591Y51232D02*
X331817D01*
G01X328832Y52730D02*
X328602Y53040D01*
X328334Y53195D01*
X328027Y53247D01*
X327644Y53144D01*
X327376Y52885D01*
X327299Y52575D01*
X327337Y52265D01*
X327491Y52007D01*
X328257Y51490D01*
X328602Y51129D01*
X328832Y50612D01*
X328909Y50147D01*
X327299D01*
G01X332162Y58021D02*
X331204Y61121D01*
X330246Y58021D01*
G01X330591Y59106D02*
X331817D01*
G01X328104Y58021D02*
Y61121D01*
X328564Y60501D01*
G01Y58021D02*
X327644D01*
G01X379421Y77600D02*
Y83900D01*
X377541D01*
X376914Y83585D01*
X376444Y82850D01*
X376287Y82010D01*
X376444Y81170D01*
X376836Y80540D01*
X377541Y80225D01*
X379421D01*
G01X373121Y77600D02*
Y83900D01*
X371162D01*
X370536Y83585D01*
X370144Y83165D01*
X369987Y82325D01*
X370144Y81485D01*
X370614Y80960D01*
X371162Y80645D01*
X373121D01*
G01X371162D02*
X369987Y77600D01*
G01X363687D02*
X366821D01*
Y83900D01*
X363687D01*
G01X364941Y80855D02*
X366821D01*
G01X360599Y78440D02*
X359972Y77915D01*
X359267Y77600D01*
X358641D01*
X358014Y77915D01*
X357544Y78440D01*
X357309Y79175D01*
X357466Y79910D01*
X357857Y80540D01*
X358562Y80960D01*
X359502Y81170D01*
X360051Y81590D01*
X360286Y82325D01*
X360129Y83060D01*
X359737Y83585D01*
X359189Y83900D01*
X358641D01*
X358092Y83690D01*
X357622Y83165D01*
G01X354299Y78440D02*
X353672Y77915D01*
X352967Y77600D01*
X352341D01*
X351714Y77915D01*
X351244Y78440D01*
X351009Y79175D01*
X351166Y79910D01*
X351557Y80540D01*
X352262Y80960D01*
X353202Y81170D01*
X353751Y81590D01*
X353986Y82325D01*
X353829Y83060D01*
X353437Y83585D01*
X352889Y83900D01*
X352341D01*
X351792Y83690D01*
X351322Y83165D01*
G01X347372Y79700D02*
X345336D01*
G01X341542Y77600D02*
Y83900D01*
X338566D01*
G01X339662Y80855D02*
X341542D01*
G01X334694Y83900D02*
X332814D01*
G01X333754D02*
Y77600D01*
G01X334694D02*
X332814D01*
G01X327454Y83900D02*
Y77600D01*
G01X329256Y83900D02*
X325652D01*
G01X316516Y86022D02*
X386792D01*
G01X374361Y21493D02*
X374591Y21648D01*
X374859Y21751D01*
X375166D01*
X375511Y21596D01*
X375779Y21338D01*
X375971Y21028D01*
X376124Y20511D01*
X376162Y20046D01*
X376086Y19581D01*
X375971Y19271D01*
X375741Y18961D01*
X375472Y18754D01*
X375204Y18651D01*
X374936D01*
X374667Y18754D01*
X374437Y18909D01*
X374246Y19116D01*
G01X372832Y21234D02*
X372602Y21544D01*
X372334Y21699D01*
X372027Y21751D01*
X371644Y21648D01*
X371376Y21389D01*
X371299Y21079D01*
X371337Y20769D01*
X371491Y20511D01*
X372257Y19994D01*
X372602Y19633D01*
X372832Y19116D01*
X372909Y18651D01*
X371299D01*
G01X374361Y13618D02*
X374591Y13773D01*
X374859Y13876D01*
X375166D01*
X375511Y13721D01*
X375779Y13463D01*
X375971Y13153D01*
X376124Y12636D01*
X376162Y12171D01*
X376086Y11706D01*
X375971Y11396D01*
X375741Y11086D01*
X375472Y10879D01*
X375204Y10776D01*
X374936D01*
X374667Y10879D01*
X374437Y11034D01*
X374246Y11241D01*
G01X372947Y11396D02*
X372717Y11034D01*
X372411Y10828D01*
X372066Y10776D01*
X371759Y10828D01*
X371452Y11086D01*
X371261Y11396D01*
X371222Y11706D01*
X371299Y12068D01*
X371567Y12326D01*
X371836Y12429D01*
X372181D01*
G01X371836D02*
X371606Y12584D01*
X371414Y12843D01*
X371337Y13153D01*
X371414Y13463D01*
X371606Y13721D01*
X371951Y13876D01*
X372296Y13824D01*
X372641Y13618D01*
G01X374361Y29367D02*
X374591Y29522D01*
X374859Y29625D01*
X375166D01*
X375511Y29470D01*
X375779Y29212D01*
X375971Y28902D01*
X376124Y28385D01*
X376162Y27920D01*
X376086Y27455D01*
X375971Y27145D01*
X375741Y26835D01*
X375472Y26628D01*
X375204Y26525D01*
X374936D01*
X374667Y26628D01*
X374437Y26783D01*
X374246Y26990D01*
G01X372104Y26525D02*
Y29625D01*
X372564Y29005D01*
G01Y26525D02*
X371644D01*
G01X455492Y24400D02*
Y17698D01*
X367894D01*
G01D02*
Y235414D01*
X455492D01*
Y51500D01*
G01X374897Y51800D02*
X374744Y51955D01*
X374629Y52214D01*
X374552Y52575D01*
X374629Y52885D01*
X374782Y53092D01*
X375051Y53247D01*
X376086D01*
Y50147D01*
X374821D01*
X374552Y50354D01*
X374399Y50664D01*
X374322Y51025D01*
X374399Y51387D01*
X374629Y51697D01*
X374897Y51800D01*
X376086D01*
G01X372832Y52730D02*
X372602Y53040D01*
X372334Y53195D01*
X372027Y53247D01*
X371644Y53144D01*
X371376Y52885D01*
X371299Y52575D01*
X371337Y52265D01*
X371491Y52007D01*
X372257Y51490D01*
X372602Y51129D01*
X372832Y50612D01*
X372909Y50147D01*
X371299D01*
G01X374897Y43926D02*
X374744Y44081D01*
X374629Y44340D01*
X374552Y44701D01*
X374629Y45011D01*
X374782Y45218D01*
X375051Y45373D01*
X376086D01*
Y42273D01*
X374821D01*
X374552Y42480D01*
X374399Y42790D01*
X374322Y43151D01*
X374399Y43513D01*
X374629Y43823D01*
X374897Y43926D01*
X376086D01*
G01X372947Y42893D02*
X372717Y42531D01*
X372411Y42325D01*
X372066Y42273D01*
X371759Y42325D01*
X371452Y42583D01*
X371261Y42893D01*
X371222Y43203D01*
X371299Y43565D01*
X371567Y43823D01*
X371836Y43926D01*
X372181D01*
G01X371836D02*
X371606Y44081D01*
X371414Y44340D01*
X371337Y44650D01*
X371414Y44960D01*
X371606Y45218D01*
X371951Y45373D01*
X372296Y45321D01*
X372641Y45115D01*
G01X374897Y59674D02*
X374744Y59829D01*
X374629Y60088D01*
X374552Y60449D01*
X374629Y60759D01*
X374782Y60966D01*
X375051Y61121D01*
X376086D01*
Y58021D01*
X374821D01*
X374552Y58228D01*
X374399Y58538D01*
X374322Y58899D01*
X374399Y59261D01*
X374629Y59571D01*
X374897Y59674D01*
X376086D01*
G01X372104Y58021D02*
Y61121D01*
X372564Y60501D01*
G01Y58021D02*
X371644D01*
G01X369456Y107439D02*
X375756D01*
Y109319D01*
X375441Y109946D01*
X374706Y110416D01*
X373866Y110573D01*
X373026Y110416D01*
X372396Y110024D01*
X372081Y109319D01*
Y107439D01*
G01X369456Y113739D02*
X375756D01*
Y115698D01*
X375441Y116324D01*
X375021Y116716D01*
X374181Y116873D01*
X373341Y116716D01*
X372816Y116246D01*
X372501Y115698D01*
Y113739D01*
G01Y115698D02*
X369456Y116873D01*
G01Y123173D02*
Y120039D01*
X375756D01*
Y123173D01*
G01X372711Y121919D02*
Y120039D01*
G01X370296Y126261D02*
X369771Y126888D01*
X369456Y127593D01*
Y128219D01*
X369771Y128846D01*
X370296Y129316D01*
X371031Y129551D01*
X371766Y129394D01*
X372396Y129003D01*
X372816Y128298D01*
X373026Y127358D01*
X373446Y126809D01*
X374181Y126574D01*
X374916Y126731D01*
X375441Y127123D01*
X375756Y127671D01*
Y128219D01*
X375546Y128768D01*
X375021Y129238D01*
G01X370296Y132561D02*
X369771Y133188D01*
X369456Y133893D01*
Y134519D01*
X369771Y135146D01*
X370296Y135616D01*
X371031Y135851D01*
X371766Y135694D01*
X372396Y135303D01*
X372816Y134598D01*
X373026Y133658D01*
X373446Y133109D01*
X374181Y132874D01*
X374916Y133031D01*
X375441Y133423D01*
X375756Y133971D01*
Y134519D01*
X375546Y135068D01*
X375021Y135538D01*
G01X371556Y139488D02*
Y141524D01*
G01X369456Y145318D02*
X375756D01*
Y148294D01*
G01X372711Y147198D02*
Y145318D01*
G01X375756Y152166D02*
Y154046D01*
G01Y153106D02*
X369456D01*
G01Y152166D02*
Y154046D01*
G01X375756Y159406D02*
X369456D01*
G01X375756Y157604D02*
Y161208D01*
G01X386792Y86022D02*
Y-52954D01*
G01X455917Y-335560D02*
X456544Y-336085D01*
X457249Y-336400D01*
X457875D01*
X458502Y-336085D01*
X458972Y-335560D01*
X459207Y-334825D01*
X459050Y-334090D01*
X458659Y-333460D01*
X457954Y-333040D01*
X457014Y-332830D01*
X456465Y-332410D01*
X456230Y-331675D01*
X456387Y-330940D01*
X456779Y-330415D01*
X457327Y-330100D01*
X457875D01*
X458424Y-330310D01*
X458894Y-330835D01*
G01X462217Y-336400D02*
Y-330100D01*
G01X465507D02*
Y-336400D01*
G01Y-333250D02*
X462217D01*
G01X469222Y-330100D02*
X471102D01*
G01X470162D02*
Y-336400D01*
G01X469222D02*
X471102D01*
G01X478029D02*
X474895D01*
Y-330100D01*
X478029D01*
G01X476775Y-333145D02*
X474895D01*
G01X480960Y-336400D02*
Y-330100D01*
X484564Y-336400D01*
Y-330100D01*
G01X488905Y-337555D02*
X489219Y-336190D01*
G01X495362Y-330100D02*
Y-336400D01*
G01X493560Y-330100D02*
X497164D01*
G01X499704Y-336400D02*
X501662Y-330100D01*
X503620Y-336400D01*
G01X502915Y-334195D02*
X500409D01*
G01X507022Y-330100D02*
X508902D01*
G01X507962D02*
Y-336400D01*
G01X507022D02*
X508902D01*
G01X511912Y-330100D02*
X513009Y-336400D01*
X514262Y-330100D01*
X515515Y-336400D01*
X516612Y-330100D01*
G01X518604Y-336400D02*
X520562Y-330100D01*
X522520Y-336400D01*
G01X521815Y-334195D02*
X519309D01*
G01X525060Y-336400D02*
Y-330100D01*
X528664Y-336400D01*
Y-330100D01*
G01X537895Y-336400D02*
Y-330100D01*
X539854D01*
X540480Y-330415D01*
X540872Y-330835D01*
X541029Y-331675D01*
X540872Y-332515D01*
X540402Y-333040D01*
X539854Y-333355D01*
X537895D01*
G01X539854D02*
X541029Y-336400D01*
G01X545762Y-336610D02*
X545605Y-336505D01*
Y-336295D01*
X545762Y-336190D01*
X545919Y-336295D01*
Y-336505D01*
X545762Y-336610D01*
G01X552062Y-336400D02*
X551435Y-336295D01*
X550887Y-335875D01*
X550417Y-335245D01*
X550104Y-334510D01*
X549947Y-333670D01*
Y-332830D01*
X550104Y-331990D01*
X550417Y-331255D01*
X550887Y-330625D01*
X551435Y-330205D01*
X552062Y-330100D01*
X552689Y-330205D01*
X553237Y-330625D01*
X553707Y-331255D01*
X554020Y-331990D01*
X554177Y-332830D01*
Y-333670D01*
X554020Y-334510D01*
X553707Y-335245D01*
X553237Y-335875D01*
X552689Y-336295D01*
X552062Y-336400D01*
G01X558362Y-336610D02*
X558205Y-336505D01*
Y-336295D01*
X558362Y-336190D01*
X558519Y-336295D01*
Y-336505D01*
X558362Y-336610D01*
G01X566385Y-330625D02*
X565915Y-330310D01*
X565367Y-330100D01*
X564740D01*
X564035Y-330415D01*
X563487Y-330940D01*
X563095Y-331570D01*
X562782Y-332620D01*
X562704Y-333565D01*
X562860Y-334510D01*
X563095Y-335140D01*
X563565Y-335770D01*
X564114Y-336190D01*
X564662Y-336400D01*
X565210D01*
X565759Y-336190D01*
X566229Y-335875D01*
X566620Y-335455D01*
G01X570962Y-336610D02*
X570805Y-336505D01*
Y-336295D01*
X570962Y-336190D01*
X571119Y-336295D01*
Y-336505D01*
X570962Y-336610D01*
G01X455839Y-326400D02*
Y-320100D01*
G01X458815D02*
X455839Y-323985D01*
G01X459285Y-326400D02*
X457170Y-322200D01*
G01X462139Y-320100D02*
Y-324615D01*
X462452Y-325560D01*
X463079Y-326190D01*
X463862Y-326400D01*
X464645Y-326190D01*
X465272Y-325560D01*
X465585Y-324615D01*
Y-320100D01*
G01X471729Y-326400D02*
X468595D01*
Y-320100D01*
X471729D01*
G01X470475Y-323145D02*
X468595D01*
G01X475522Y-320100D02*
X477402D01*
G01X476462D02*
Y-326400D01*
G01X475522D02*
X477402D01*
G01X487417Y-325560D02*
X488044Y-326085D01*
X488749Y-326400D01*
X489375D01*
X490002Y-326085D01*
X490472Y-325560D01*
X490707Y-324825D01*
X490550Y-324090D01*
X490159Y-323460D01*
X489454Y-323040D01*
X488514Y-322830D01*
X487965Y-322410D01*
X487730Y-321675D01*
X487887Y-320940D01*
X488279Y-320415D01*
X488827Y-320100D01*
X489375D01*
X489924Y-320310D01*
X490394Y-320835D01*
G01X493717Y-326400D02*
Y-320100D01*
G01X497007D02*
Y-326400D01*
G01Y-323250D02*
X493717D01*
G01X499704Y-326400D02*
X501662Y-320100D01*
X503620Y-326400D01*
G01X502915Y-324195D02*
X500409D01*
G01X506160Y-326400D02*
Y-320100D01*
X509764Y-326400D01*
Y-320100D01*
G01X518917Y-326400D02*
Y-320100D01*
G01X522207D02*
Y-326400D01*
G01Y-323250D02*
X518917D01*
G01X525217Y-325560D02*
X525844Y-326085D01*
X526549Y-326400D01*
X527175D01*
X527802Y-326085D01*
X528272Y-325560D01*
X528507Y-324825D01*
X528350Y-324090D01*
X527959Y-323460D01*
X527254Y-323040D01*
X526314Y-322830D01*
X525765Y-322410D01*
X525530Y-321675D01*
X525687Y-320940D01*
X526079Y-320415D01*
X526627Y-320100D01*
X527175D01*
X527724Y-320310D01*
X528194Y-320835D01*
G01X532222Y-320100D02*
X534102D01*
G01X533162D02*
Y-326400D01*
G01X532222D02*
X534102D01*
G01X537504D02*
X539462Y-320100D01*
X541420Y-326400D01*
G01X540715Y-324195D02*
X538209D01*
G01X543960Y-326400D02*
Y-320100D01*
X547564Y-326400D01*
Y-320100D01*
G01X552532Y-323250D02*
X554099D01*
Y-325140D01*
X553629Y-325770D01*
X553080Y-326190D01*
X552297Y-326400D01*
X551514Y-326190D01*
X550965Y-325770D01*
X550495Y-325140D01*
X550182Y-324405D01*
X550025Y-323565D01*
Y-322830D01*
X550182Y-322200D01*
X550495Y-321465D01*
X550965Y-320835D01*
X551435Y-320415D01*
X552062Y-320100D01*
X552610D01*
X553237Y-320310D01*
X553707Y-320730D01*
G01X558205Y-327555D02*
X558519Y-326190D01*
G01X564662Y-320100D02*
Y-326400D01*
G01X562860Y-320100D02*
X566464D01*
G01X569004Y-326400D02*
X570962Y-320100D01*
X572920Y-326400D01*
G01X572215Y-324195D02*
X569709D01*
G01X577262Y-326400D02*
X576635Y-326295D01*
X576087Y-325875D01*
X575617Y-325245D01*
X575304Y-324510D01*
X575147Y-323670D01*
Y-322830D01*
X575304Y-321990D01*
X575617Y-321255D01*
X576087Y-320625D01*
X576635Y-320205D01*
X577262Y-320100D01*
X577889Y-320205D01*
X578437Y-320625D01*
X578907Y-321255D01*
X579220Y-321990D01*
X579377Y-322830D01*
Y-323670D01*
X579220Y-324510D01*
X578907Y-325245D01*
X578437Y-325875D01*
X577889Y-326295D01*
X577262Y-326400D01*
G01X589862D02*
Y-323565D01*
X588295Y-320100D01*
G01X591429D02*
X589862Y-323565D01*
G01X594439Y-320100D02*
Y-324615D01*
X594752Y-325560D01*
X595379Y-326190D01*
X596162Y-326400D01*
X596945Y-326190D01*
X597572Y-325560D01*
X597885Y-324615D01*
Y-320100D01*
G01X600504Y-326400D02*
X602462Y-320100D01*
X604420Y-326400D01*
G01X603715Y-324195D02*
X601209D01*
G01X606960Y-326400D02*
Y-320100D01*
X610564Y-326400D01*
Y-320100D01*
G01X455760Y-316400D02*
Y-310100D01*
X459364Y-316400D01*
Y-310100D01*
G01X463862Y-316400D02*
X463235Y-316295D01*
X462687Y-315875D01*
X462217Y-315245D01*
X461904Y-314510D01*
X461747Y-313670D01*
Y-312830D01*
X461904Y-311990D01*
X462217Y-311255D01*
X462687Y-310625D01*
X463235Y-310205D01*
X463862Y-310100D01*
X464489Y-310205D01*
X465037Y-310625D01*
X465507Y-311255D01*
X465820Y-311990D01*
X465977Y-312830D01*
Y-313670D01*
X465820Y-314510D01*
X465507Y-315245D01*
X465037Y-315875D01*
X464489Y-316295D01*
X463862Y-316400D01*
G01X470162Y-316610D02*
X470005Y-316505D01*
Y-316295D01*
X470162Y-316190D01*
X470319Y-316295D01*
Y-316505D01*
X470162Y-316610D01*
G01X476462Y-316400D02*
Y-310100D01*
X475522Y-311360D01*
G01Y-316400D02*
X477402D01*
G01X482762D02*
X483310Y-316295D01*
X483937Y-315980D01*
X484329Y-315455D01*
X484485Y-314720D01*
X484329Y-313985D01*
X483859Y-313355D01*
X483154Y-313040D01*
X482370D01*
X481900Y-312830D01*
X481509Y-312305D01*
X481352Y-311570D01*
X481587Y-310835D01*
X482135Y-310310D01*
X482762Y-310100D01*
X483389Y-310310D01*
X483937Y-310835D01*
X484172Y-311570D01*
X484015Y-312305D01*
X483624Y-312830D01*
X483154Y-313040D01*
X482370D01*
X481665Y-313355D01*
X481195Y-313985D01*
X481039Y-314720D01*
X481195Y-315455D01*
X481587Y-315980D01*
X482214Y-316295D01*
X482762Y-316400D01*
G01X489062D02*
X489610Y-316295D01*
X490237Y-315980D01*
X490629Y-315455D01*
X490785Y-314720D01*
X490629Y-313985D01*
X490159Y-313355D01*
X489454Y-313040D01*
X488670D01*
X488200Y-312830D01*
X487809Y-312305D01*
X487652Y-311570D01*
X487887Y-310835D01*
X488435Y-310310D01*
X489062Y-310100D01*
X489689Y-310310D01*
X490237Y-310835D01*
X490472Y-311570D01*
X490315Y-312305D01*
X489924Y-312830D01*
X489454Y-313040D01*
X488670D01*
X487965Y-313355D01*
X487495Y-313985D01*
X487339Y-314720D01*
X487495Y-315455D01*
X487887Y-315980D01*
X488514Y-316295D01*
X489062Y-316400D01*
G01X495205Y-317555D02*
X495519Y-316190D01*
G01X499312Y-310100D02*
X500409Y-316400D01*
X501662Y-310100D01*
X502915Y-316400D01*
X504012Y-310100D01*
G01X509529Y-316400D02*
X506395D01*
Y-310100D01*
X509529D01*
G01X508275Y-313145D02*
X506395D01*
G01X512460Y-316400D02*
Y-310100D01*
X516064Y-316400D01*
Y-310100D01*
G01X525217Y-316400D02*
Y-310100D01*
G01X528507D02*
Y-316400D01*
G01Y-313250D02*
X525217D01*
G01X530812Y-310100D02*
X531909Y-316400D01*
X533162Y-310100D01*
X534415Y-316400D01*
X535512Y-310100D01*
G01X537504Y-316400D02*
X539462Y-310100D01*
X541420Y-316400D01*
G01X540715Y-314195D02*
X538209D01*
G01X550574Y-311150D02*
X551044Y-310520D01*
X551592Y-310205D01*
X552219Y-310100D01*
X553002Y-310310D01*
X553550Y-310835D01*
X553707Y-311465D01*
X553629Y-312095D01*
X553315Y-312620D01*
X551749Y-313670D01*
X551044Y-314405D01*
X550574Y-315455D01*
X550417Y-316400D01*
X553707D01*
G01X556560D02*
Y-310100D01*
X560164Y-316400D01*
Y-310100D01*
G01X562939Y-316400D02*
Y-310100D01*
X564505D01*
X565132Y-310415D01*
X565602Y-310835D01*
X565994Y-311465D01*
X566307Y-312200D01*
X566385Y-313250D01*
X566307Y-314300D01*
X565994Y-315035D01*
X565602Y-315665D01*
X565132Y-316085D01*
X564505Y-316400D01*
X562939D01*
G01X575695D02*
Y-310100D01*
X577654D01*
X578280Y-310415D01*
X578672Y-310835D01*
X578829Y-311675D01*
X578672Y-312515D01*
X578202Y-313040D01*
X577654Y-313355D01*
X575695D01*
G01X577654D02*
X578829Y-316400D01*
G01X581839D02*
Y-310100D01*
X583405D01*
X584032Y-310415D01*
X584502Y-310835D01*
X584894Y-311465D01*
X585207Y-312200D01*
X585285Y-313250D01*
X585207Y-314300D01*
X584894Y-315035D01*
X584502Y-315665D01*
X584032Y-316085D01*
X583405Y-316400D01*
X581839D01*
G01X589862Y-316610D02*
X589705Y-316505D01*
Y-316295D01*
X589862Y-316190D01*
X590019Y-316295D01*
Y-316505D01*
X589862Y-316610D01*
G01X450906Y-49508D02*
X521772D01*
Y14400D01*
G01X450906Y24400D02*
Y-49508D01*
G01X455492Y40100D02*
Y29900D01*
G01X450906Y35600D02*
Y29100D01*
G01X455492Y46100D02*
Y40100D01*
G01X450906Y79300D02*
Y50900D01*
G01X515399Y65354D02*
Y71654D01*
X513519D01*
X512892Y71339D01*
X512422Y70604D01*
X512265Y69764D01*
X512422Y68924D01*
X512814Y68294D01*
X513519Y67979D01*
X515399D01*
G01X509099Y65354D02*
Y71654D01*
X507140D01*
X506514Y71339D01*
X506122Y70919D01*
X505965Y70079D01*
X506122Y69239D01*
X506592Y68714D01*
X507140Y68399D01*
X509099D01*
G01X507140D02*
X505965Y65354D01*
G01X499665D02*
X502799D01*
Y71654D01*
X499665D01*
G01X500919Y68609D02*
X502799D01*
G01X496577Y66194D02*
X495950Y65669D01*
X495245Y65354D01*
X494619D01*
X493992Y65669D01*
X493522Y66194D01*
X493287Y66929D01*
X493444Y67664D01*
X493835Y68294D01*
X494540Y68714D01*
X495480Y68924D01*
X496029Y69344D01*
X496264Y70079D01*
X496107Y70814D01*
X495715Y71339D01*
X495167Y71654D01*
X494619D01*
X494070Y71444D01*
X493600Y70919D01*
G01X490277Y66194D02*
X489650Y65669D01*
X488945Y65354D01*
X488319D01*
X487692Y65669D01*
X487222Y66194D01*
X486987Y66929D01*
X487144Y67664D01*
X487535Y68294D01*
X488240Y68714D01*
X489180Y68924D01*
X489729Y69344D01*
X489964Y70079D01*
X489807Y70814D01*
X489415Y71339D01*
X488867Y71654D01*
X488319D01*
X487770Y71444D01*
X487300Y70919D01*
G01X483350Y67454D02*
X481314D01*
G01X477520Y65354D02*
Y71654D01*
X474544D01*
G01X475640Y68609D02*
X477520D01*
G01X470672Y71654D02*
X468792D01*
G01X469732D02*
Y65354D01*
G01X470672D02*
X468792D01*
G01X463432Y71654D02*
Y65354D01*
G01X465234Y71654D02*
X461630D01*
G01X521772Y63800D02*
Y80611D01*
X465400D01*
G01X461600D02*
X453200D01*
G01X463306Y115354D02*
X463153Y115509D01*
X463038Y115768D01*
X462961Y116129D01*
X463038Y116439D01*
X463191Y116646D01*
X463460Y116801D01*
X464495D01*
Y113701D01*
X463230D01*
X462961Y113908D01*
X462808Y114218D01*
X462731Y114579D01*
X462808Y114941D01*
X463038Y115251D01*
X463306Y115354D01*
X464495D01*
G01X460513Y113701D02*
Y116801D01*
X460973Y116181D01*
G01Y113701D02*
X460053D01*
G01X464471Y140216D02*
X463513Y143316D01*
X462555Y140216D01*
G01X462900Y141301D02*
X464126D01*
G01X460413Y140216D02*
X460145Y140268D01*
X459838Y140423D01*
X459646Y140681D01*
X459570Y141043D01*
X459646Y141404D01*
X459876Y141714D01*
X460221Y141869D01*
X460605D01*
X460835Y141973D01*
X461026Y142231D01*
X461103Y142593D01*
X460988Y142954D01*
X460720Y143213D01*
X460413Y143316D01*
X460106Y143213D01*
X459838Y142954D01*
X459723Y142593D01*
X459800Y142231D01*
X459991Y141973D01*
X460221Y141869D01*
X460605D01*
X460950Y141714D01*
X461180Y141404D01*
X461256Y141043D01*
X461180Y140681D01*
X460988Y140423D01*
X460681Y140268D01*
X460413Y140216D01*
G01X467469Y126054D02*
X467316Y126209D01*
X467201Y126468D01*
X467124Y126829D01*
X467201Y127139D01*
X467354Y127346D01*
X467623Y127501D01*
X468658D01*
Y124401D01*
X467393D01*
X467124Y124608D01*
X466971Y124918D01*
X466894Y125279D01*
X466971Y125641D01*
X467201Y125951D01*
X467469Y126054D01*
X468658D01*
G01X465404Y126984D02*
X465174Y127294D01*
X464906Y127449D01*
X464599Y127501D01*
X464216Y127398D01*
X463948Y127139D01*
X463871Y126829D01*
X463909Y126519D01*
X464063Y126261D01*
X464829Y125744D01*
X465174Y125383D01*
X465404Y124866D01*
X465481Y124401D01*
X463871D01*
G01X469534Y149805D02*
X468576Y152905D01*
X467618Y149805D01*
G01X467963Y150890D02*
X469189D01*
G01X465553Y149805D02*
X465476Y150477D01*
X465361Y151045D01*
X465208Y151562D01*
X465016Y152130D01*
X464709Y152905D01*
X466243D01*
G01X479862Y-303700D02*
X477342Y-303283D01*
X475137Y-301617D01*
X473247Y-299117D01*
X471987Y-296200D01*
X471357Y-292867D01*
Y-289533D01*
X471987Y-286200D01*
X473247Y-283283D01*
X475137Y-280784D01*
X477342Y-279117D01*
X479862Y-278700D01*
X482382Y-279117D01*
X484587Y-280784D01*
X486477Y-283283D01*
X487737Y-286200D01*
X488367Y-289533D01*
Y-292867D01*
X487737Y-296200D01*
X486477Y-299117D01*
X484587Y-301617D01*
X482382Y-303283D01*
X479862Y-303700D01*
G01X482382Y-297033D02*
X486162Y-303700D01*
G01X499707Y-287034D02*
Y-298700D01*
X500967Y-301617D01*
X502857Y-303283D01*
X505062Y-303700D01*
X507267Y-303283D01*
X509157Y-301617D01*
X510417Y-298700D01*
G01Y-303700D02*
Y-287034D01*
G01X535932Y-303700D02*
Y-287034D01*
G01Y-289950D02*
X534672Y-288284D01*
X532782Y-287450D01*
X530577Y-287034D01*
X528372Y-287867D01*
X526482Y-289533D01*
X525222Y-292034D01*
X524592Y-295367D01*
X525222Y-298700D01*
X526482Y-301201D01*
X528372Y-302867D01*
X530577Y-303700D01*
X532782Y-303283D01*
X534672Y-302034D01*
X535932Y-300367D01*
G01X550107Y-303700D02*
Y-287034D01*
G01Y-291200D02*
X551367Y-289117D01*
X553257Y-287450D01*
X555777Y-287034D01*
X557982Y-287450D01*
X559872Y-289117D01*
X560817Y-292034D01*
Y-303700D01*
G01X580662Y-278700D02*
Y-303700D01*
G01X576252Y-287034D02*
X585072D01*
G01X611532Y-303700D02*
Y-287034D01*
G01Y-289950D02*
X610272Y-288284D01*
X608382Y-287450D01*
X606177Y-287034D01*
X603972Y-287867D01*
X602082Y-289533D01*
X600822Y-292034D01*
X600192Y-295367D01*
X600822Y-298700D01*
X602082Y-301201D01*
X603972Y-302867D01*
X606177Y-303700D01*
X608382Y-303283D01*
X610272Y-302034D01*
X611532Y-300367D01*
G01X513604Y6499D02*
X512646Y9599D01*
X511688Y6499D01*
G01X512033Y7584D02*
X513259D01*
G01X510416Y29747D02*
X511950D01*
Y32847D01*
X510416D01*
G01X511030Y31349D02*
X511950D01*
G01X511976Y13036D02*
X511823Y13191D01*
X511708Y13450D01*
X511631Y13811D01*
X511708Y14121D01*
X511861Y14328D01*
X512130Y14483D01*
X513165D01*
Y11383D01*
X511900D01*
X511631Y11590D01*
X511478Y11900D01*
X511401Y12261D01*
X511478Y12623D01*
X511708Y12933D01*
X511976Y13036D01*
X513165D01*
G01X515126Y23659D02*
Y26759D01*
X514360D01*
X514053Y26604D01*
X513823Y26397D01*
X513631Y26087D01*
X513478Y25726D01*
X513440Y25209D01*
X513478Y24692D01*
X513631Y24331D01*
X513823Y24021D01*
X514053Y23814D01*
X514360Y23659D01*
X515126D01*
G01X508740Y17313D02*
X508970Y17468D01*
X509238Y17571D01*
X509545D01*
X509890Y17416D01*
X510158Y17158D01*
X510350Y16848D01*
X510503Y16331D01*
X510541Y15866D01*
X510465Y15401D01*
X510350Y15091D01*
X510120Y14781D01*
X509851Y14574D01*
X509583Y14471D01*
X509315D01*
X509046Y14574D01*
X508816Y14729D01*
X508625Y14936D01*
G01X511312Y49488D02*
Y46388D01*
G01X512922D02*
Y49488D01*
G01Y47938D02*
X511312D01*
G01X511153Y39673D02*
X510386D01*
Y38743D01*
X510616Y38433D01*
X510885Y38226D01*
X511268Y38123D01*
X511651Y38226D01*
X511920Y38433D01*
X512150Y38743D01*
X512303Y39105D01*
X512380Y39518D01*
Y39880D01*
X512303Y40190D01*
X512150Y40551D01*
X511920Y40861D01*
X511690Y41068D01*
X511383Y41223D01*
X511115D01*
X510808Y41120D01*
X510578Y40913D01*
G01X511811Y33535D02*
Y36635D01*
X510355D01*
G01X510891Y35137D02*
X511811D01*
G01X511657Y51900D02*
X512577D01*
G01X512117D02*
Y55000D01*
G01X511657D02*
X512577D01*
G01X506499Y115254D02*
X506346Y115409D01*
X506231Y115668D01*
X506154Y116029D01*
X506231Y116339D01*
X506384Y116546D01*
X506653Y116701D01*
X507688D01*
Y113601D01*
X506423D01*
X506154Y113808D01*
X506001Y114118D01*
X505924Y114479D01*
X506001Y114841D01*
X506231Y115151D01*
X506499Y115254D01*
X507688D01*
G01X503783Y113601D02*
X503706Y114273D01*
X503591Y114841D01*
X503438Y115358D01*
X503246Y115926D01*
X502939Y116701D01*
X504473D01*
G01X507864Y139892D02*
X506906Y142992D01*
X505948Y139892D01*
G01X506293Y140977D02*
X507519D01*
G01X504534Y142475D02*
X504304Y142785D01*
X504036Y142940D01*
X503729Y142992D01*
X503346Y142889D01*
X503078Y142630D01*
X503001Y142320D01*
X503039Y142010D01*
X503193Y141752D01*
X503959Y141235D01*
X504304Y140874D01*
X504534Y140357D01*
X504611Y139892D01*
X503001D01*
G01X511662Y125654D02*
X511509Y125809D01*
X511394Y126068D01*
X511317Y126429D01*
X511394Y126739D01*
X511547Y126946D01*
X511816Y127101D01*
X512851D01*
Y124001D01*
X511586D01*
X511317Y124208D01*
X511164Y124518D01*
X511087Y124879D01*
X511164Y125241D01*
X511394Y125551D01*
X511662Y125654D01*
X512851D01*
G01X508869Y124001D02*
X508601Y124053D01*
X508294Y124208D01*
X508102Y124466D01*
X508026Y124828D01*
X508102Y125189D01*
X508332Y125499D01*
X508677Y125654D01*
X509061D01*
X509291Y125758D01*
X509482Y126016D01*
X509559Y126378D01*
X509444Y126739D01*
X509176Y126998D01*
X508869Y127101D01*
X508562Y126998D01*
X508294Y126739D01*
X508179Y126378D01*
X508256Y126016D01*
X508447Y125758D01*
X508677Y125654D01*
X509061D01*
X509406Y125499D01*
X509636Y125189D01*
X509712Y124828D01*
X509636Y124466D01*
X509444Y124208D01*
X509137Y124053D01*
X508869Y124001D01*
G01X512127Y149916D02*
X511169Y153016D01*
X510211Y149916D01*
G01X510556Y151001D02*
X511782D01*
G01X508069Y149916D02*
Y153016D01*
X508529Y152396D01*
G01Y149916D02*
X507609D01*
G01X521772Y25000D02*
Y30372D01*
G01X517186Y25200D02*
Y29800D01*
G01X604784Y105300D02*
Y17698D01*
X523900D01*
G01X517186Y22600D02*
Y25200D01*
G01X521772Y21500D02*
Y25000D01*
G01Y63800D02*
Y43500D01*
G01X517186Y46500D02*
Y85600D01*
G01X521772Y38800D02*
Y43500D01*
G01X517186Y89300D02*
Y235414D01*
X604784D01*
Y109400D01*
G01X599297Y40283D02*
Y43383D01*
X599757Y42763D01*
G01Y40283D02*
X598837D01*
G01X596264Y110939D02*
X602564D01*
Y112819D01*
X602249Y113446D01*
X601514Y113916D01*
X600674Y114073D01*
X599834Y113916D01*
X599204Y113524D01*
X598889Y112819D01*
Y110939D01*
G01X596264Y117239D02*
X602564D01*
Y119198D01*
X602249Y119824D01*
X601829Y120216D01*
X600989Y120373D01*
X600149Y120216D01*
X599624Y119746D01*
X599309Y119198D01*
Y117239D01*
G01Y119198D02*
X596264Y120373D01*
G01Y126673D02*
Y123539D01*
X602564D01*
Y126673D01*
G01X599519Y125419D02*
Y123539D01*
G01X597104Y129761D02*
X596579Y130388D01*
X596264Y131093D01*
Y131719D01*
X596579Y132346D01*
X597104Y132816D01*
X597839Y133051D01*
X598574Y132894D01*
X599204Y132503D01*
X599624Y131798D01*
X599834Y130858D01*
X600254Y130309D01*
X600989Y130074D01*
X601724Y130231D01*
X602249Y130623D01*
X602564Y131171D01*
Y131719D01*
X602354Y132268D01*
X601829Y132738D01*
G01X597104Y136061D02*
X596579Y136688D01*
X596264Y137393D01*
Y138019D01*
X596579Y138646D01*
X597104Y139116D01*
X597839Y139351D01*
X598574Y139194D01*
X599204Y138803D01*
X599624Y138098D01*
X599834Y137158D01*
X600254Y136609D01*
X600989Y136374D01*
X601724Y136531D01*
X602249Y136923D01*
X602564Y137471D01*
Y138019D01*
X602354Y138568D01*
X601829Y139038D01*
G01X598364Y142988D02*
Y145024D01*
G01X596264Y148818D02*
X602564D01*
Y151794D01*
G01X599519Y150698D02*
Y148818D01*
G01X602564Y155666D02*
Y157546D01*
G01Y156606D02*
X596264D01*
G01Y155666D02*
Y157546D01*
G01X602564Y162906D02*
X596264D01*
G01X602564Y161104D02*
Y164708D01*
G01X630408Y109138D02*
X629641D01*
Y108208D01*
X629871Y107898D01*
X630140Y107691D01*
X630523Y107588D01*
X630906Y107691D01*
X631175Y107898D01*
X631405Y108208D01*
X631558Y108570D01*
X631635Y108983D01*
Y109345D01*
X631558Y109655D01*
X631405Y110016D01*
X631175Y110326D01*
X630945Y110533D01*
X630638Y110688D01*
X630370D01*
X630063Y110585D01*
X629833Y110378D01*
G01X628381Y108208D02*
X628151Y107846D01*
X627845Y107640D01*
X627500Y107588D01*
X627193Y107640D01*
X626886Y107898D01*
X626695Y108208D01*
X626656Y108518D01*
X626733Y108880D01*
X627001Y109138D01*
X627270Y109241D01*
X627615D01*
G01X627270D02*
X627040Y109396D01*
X626848Y109655D01*
X626771Y109965D01*
X626848Y110275D01*
X627040Y110533D01*
X627385Y110688D01*
X627730Y110636D01*
X628075Y110430D01*
G01X630308Y168261D02*
X629541D01*
Y167331D01*
X629771Y167021D01*
X630040Y166814D01*
X630423Y166711D01*
X630806Y166814D01*
X631075Y167021D01*
X631305Y167331D01*
X631458Y167693D01*
X631535Y168106D01*
Y168468D01*
X631458Y168778D01*
X631305Y169139D01*
X631075Y169449D01*
X630845Y169656D01*
X630538Y169811D01*
X630270D01*
X629963Y169708D01*
X629733Y169501D01*
G01X627438Y166711D02*
Y169811D01*
X627898Y169191D01*
G01Y166711D02*
X626978D01*
G01X651212Y-283400D02*
Y-291400D01*
X655212D01*
G01X663012D02*
Y-286067D01*
G01Y-287000D02*
X662612Y-286467D01*
X662012Y-286200D01*
X661312Y-286067D01*
X660612Y-286333D01*
X660012Y-286867D01*
X659612Y-287667D01*
X659412Y-288733D01*
X659612Y-289800D01*
X660012Y-290600D01*
X660612Y-291133D01*
X661312Y-291400D01*
X662012Y-291267D01*
X662612Y-290867D01*
X663012Y-290334D01*
G01X667112Y-293800D02*
X667712Y-294067D01*
X668512Y-293800D01*
X669012Y-293267D01*
X669412Y-292600D01*
X670012Y-290467D01*
X671312Y-286067D01*
G01X668112D02*
X670012Y-290467D01*
G01X675712Y-287800D02*
X678912D01*
X678612Y-286867D01*
X678112Y-286333D01*
X677412Y-286067D01*
X676712Y-286200D01*
X676112Y-286600D01*
X675712Y-287533D01*
X675512Y-288334D01*
Y-289133D01*
X675712Y-289933D01*
X676212Y-290733D01*
X676812Y-291267D01*
X677512Y-291400D01*
X678212Y-291133D01*
X678912Y-290334D01*
G01X683812Y-291400D02*
Y-286067D01*
G01Y-287133D02*
X684312Y-286600D01*
X684812Y-286200D01*
X685512Y-286067D01*
X686012Y-286200D01*
X686612Y-286600D01*
G01X633425Y-49508D02*
X704291D01*
Y80611D01*
X633425D01*
Y-49508D01*
G01X649955Y3091D02*
X649687Y3452D01*
X649457Y3659D01*
X649150Y3762D01*
X648882Y3659D01*
X648690Y3452D01*
X648537Y3142D01*
X648499Y2781D01*
X648537Y2471D01*
X648690Y2161D01*
X648920Y1902D01*
X649189Y1799D01*
X649495Y1902D01*
X649764Y2212D01*
X649917Y2677D01*
X649955Y3194D01*
X649879Y3866D01*
X649764Y4227D01*
X649572Y4589D01*
X649304Y4847D01*
X649035Y4899D01*
X648767Y4796D01*
X648575Y4537D01*
G01X635473Y8901D02*
X641773D01*
Y10781D01*
X641458Y11408D01*
X640723Y11878D01*
X639883Y12035D01*
X639043Y11878D01*
X638413Y11486D01*
X638098Y10781D01*
Y8901D01*
G01X635473Y15201D02*
X641773D01*
Y17160D01*
X641458Y17786D01*
X641038Y18178D01*
X640198Y18335D01*
X639358Y18178D01*
X638833Y17708D01*
X638518Y17160D01*
Y15201D01*
G01Y17160D02*
X635473Y18335D01*
G01Y24635D02*
Y21501D01*
X641773D01*
Y24635D01*
G01X638728Y23381D02*
Y21501D01*
G01X636313Y27723D02*
X635788Y28350D01*
X635473Y29055D01*
Y29681D01*
X635788Y30308D01*
X636313Y30778D01*
X637048Y31013D01*
X637783Y30856D01*
X638413Y30465D01*
X638833Y29760D01*
X639043Y28820D01*
X639463Y28271D01*
X640198Y28036D01*
X640933Y28193D01*
X641458Y28585D01*
X641773Y29133D01*
Y29681D01*
X641563Y30230D01*
X641038Y30700D01*
G01X636313Y34023D02*
X635788Y34650D01*
X635473Y35355D01*
Y35981D01*
X635788Y36608D01*
X636313Y37078D01*
X637048Y37313D01*
X637783Y37156D01*
X638413Y36765D01*
X638833Y36060D01*
X639043Y35120D01*
X639463Y34571D01*
X640198Y34336D01*
X640933Y34493D01*
X641458Y34885D01*
X641773Y35433D01*
Y35981D01*
X641563Y36530D01*
X641038Y37000D01*
G01X637573Y40950D02*
Y42986D01*
G01X635473Y46780D02*
X641773D01*
Y49756D01*
G01X638728Y48660D02*
Y46780D01*
G01X641773Y53628D02*
Y55508D01*
G01Y54568D02*
X635473D01*
G01Y53628D02*
Y55508D01*
G01X641773Y60868D02*
X635473D01*
G01X641773Y59066D02*
Y62670D01*
G01X634708Y132761D02*
X633941D01*
Y131831D01*
X634171Y131521D01*
X634440Y131314D01*
X634823Y131211D01*
X635206Y131314D01*
X635475Y131521D01*
X635705Y131831D01*
X635858Y132193D01*
X635935Y132606D01*
Y132968D01*
X635858Y133278D01*
X635705Y133639D01*
X635475Y133949D01*
X635245Y134156D01*
X634938Y134311D01*
X634670D01*
X634363Y134208D01*
X634133Y134001D01*
G01X632566Y133794D02*
X632336Y134104D01*
X632068Y134259D01*
X631761Y134311D01*
X631378Y134208D01*
X631110Y133949D01*
X631033Y133639D01*
X631071Y133329D01*
X631225Y133071D01*
X631991Y132554D01*
X632336Y132193D01*
X632566Y131676D01*
X632643Y131211D01*
X631033D01*
G01X673512Y-333400D02*
X675912D01*
G01X674712D02*
Y-341400D01*
G01X673512D02*
X675912D01*
G01X681312D02*
Y-336067D01*
G01Y-337133D02*
X681812Y-336600D01*
X682312Y-336200D01*
X683012Y-336067D01*
X683512Y-336200D01*
X684112Y-336600D01*
G01X689212Y-337800D02*
X692412D01*
X692112Y-336867D01*
X691612Y-336333D01*
X690912Y-336067D01*
X690212Y-336200D01*
X689612Y-336600D01*
X689212Y-337533D01*
X689012Y-338334D01*
Y-339133D01*
X689212Y-339933D01*
X689712Y-340733D01*
X690312Y-341267D01*
X691012Y-341400D01*
X691712Y-341133D01*
X692412Y-340334D01*
G01X697012Y-341400D02*
Y-336067D01*
G01Y-337400D02*
X697412Y-336733D01*
X698012Y-336200D01*
X698812Y-336067D01*
X699512Y-336200D01*
X700112Y-336733D01*
X700412Y-337667D01*
Y-341400D01*
G01X705212Y-337800D02*
X708412D01*
X708112Y-336867D01*
X707612Y-336333D01*
X706912Y-336067D01*
X706212Y-336200D01*
X705612Y-336600D01*
X705212Y-337533D01*
X705012Y-338334D01*
Y-339133D01*
X705212Y-339933D01*
X705712Y-340733D01*
X706312Y-341267D01*
X707012Y-341400D01*
X707712Y-341133D01*
X708412Y-340334D01*
G01X662612Y-315334D02*
X663412Y-316000D01*
X664312Y-316400D01*
X665112D01*
X665912Y-316000D01*
X666512Y-315334D01*
X666812Y-314400D01*
X666612Y-313467D01*
X666112Y-312667D01*
X665212Y-312133D01*
X664012Y-311867D01*
X663312Y-311333D01*
X663012Y-310400D01*
X663212Y-309467D01*
X663712Y-308800D01*
X664412Y-308400D01*
X665112D01*
X665812Y-308667D01*
X666412Y-309333D01*
G01X671512Y-308400D02*
X673912D01*
G01X672712D02*
Y-316400D01*
G01X671512D02*
X673912D01*
G01X678712Y-308400D02*
Y-316400D01*
X682712D01*
G01X686512D02*
Y-308400D01*
G01X690312D02*
X686512Y-313334D01*
G01X690912Y-316400D02*
X688212Y-311067D01*
G01X695412Y-313733D02*
X698012D01*
G01X705512Y-312133D02*
X705912Y-311733D01*
X706212Y-311067D01*
X706412Y-310133D01*
X706212Y-309333D01*
X705812Y-308800D01*
X705112Y-308400D01*
X702412D01*
Y-316400D01*
X705712D01*
X706412Y-315867D01*
X706812Y-315067D01*
X707012Y-314133D01*
X706812Y-313200D01*
X706212Y-312400D01*
X705512Y-312133D01*
X702412D01*
G01X712712Y-316400D02*
X711912Y-316267D01*
X711212Y-315733D01*
X710612Y-314933D01*
X710212Y-314000D01*
X710012Y-312933D01*
Y-311867D01*
X710212Y-310800D01*
X710612Y-309867D01*
X711212Y-309067D01*
X711912Y-308533D01*
X712712Y-308400D01*
X713512Y-308533D01*
X714212Y-309067D01*
X714812Y-309867D01*
X715212Y-310800D01*
X715412Y-311867D01*
Y-312933D01*
X715212Y-314000D01*
X714812Y-314933D01*
X714212Y-315733D01*
X713512Y-316267D01*
X712712Y-316400D01*
G01X720712Y-308400D02*
Y-316400D01*
G01X718412Y-308400D02*
X723012D01*
G01X664467Y1599D02*
Y4699D01*
X665885Y2477D01*
X663969D01*
G01X657770Y2364D02*
X657540Y2106D01*
X657272Y1951D01*
X656927Y1899D01*
X656582Y2002D01*
X656314Y2209D01*
X656122Y2571D01*
X656084Y2984D01*
X656160Y3397D01*
X656352Y3656D01*
X656620Y3862D01*
X656889Y3914D01*
X657157Y3862D01*
X657502Y3656D01*
X657387Y4999D01*
X656352D01*
G01X673670Y2219D02*
X673440Y1857D01*
X673134Y1651D01*
X672789Y1599D01*
X672482Y1651D01*
X672175Y1909D01*
X671984Y2219D01*
X671945Y2529D01*
X672022Y2891D01*
X672290Y3149D01*
X672559Y3252D01*
X672904D01*
G01X672559D02*
X672329Y3407D01*
X672137Y3666D01*
X672060Y3976D01*
X672137Y4286D01*
X672329Y4544D01*
X672674Y4699D01*
X673019Y4647D01*
X673364Y4441D01*
G01X695585Y6599D02*
X694627Y9699D01*
X693669Y6599D01*
G01X694014Y7684D02*
X695240D01*
G01X688527Y2099D02*
Y5199D01*
X688987Y4579D01*
G01Y2099D02*
X688067D01*
G01X681555Y4282D02*
X681325Y4592D01*
X681057Y4747D01*
X680750Y4799D01*
X680367Y4696D01*
X680099Y4437D01*
X680022Y4127D01*
X680060Y3817D01*
X680214Y3559D01*
X680980Y3042D01*
X681325Y2681D01*
X681555Y2164D01*
X681632Y1699D01*
X680022D01*
G01X693997Y28647D02*
X695531D01*
Y31747D01*
X693997D01*
G01X694611Y30249D02*
X695531D01*
G01X694357Y13936D02*
X694204Y14091D01*
X694089Y14350D01*
X694012Y14711D01*
X694089Y15021D01*
X694242Y15228D01*
X694511Y15383D01*
X695546D01*
Y12283D01*
X694281D01*
X694012Y12490D01*
X693859Y12800D01*
X693782Y13161D01*
X693859Y13523D01*
X694089Y13833D01*
X694357Y13936D01*
X695546D01*
G01X695407Y23359D02*
Y26459D01*
X694641D01*
X694334Y26304D01*
X694104Y26097D01*
X693912Y25787D01*
X693759Y25426D01*
X693721Y24909D01*
X693759Y24392D01*
X693912Y24031D01*
X694104Y23721D01*
X694334Y23514D01*
X694641Y23359D01*
X695407D01*
G01X694021Y20613D02*
X694251Y20768D01*
X694519Y20871D01*
X694826D01*
X695171Y20716D01*
X695439Y20458D01*
X695631Y20148D01*
X695784Y19631D01*
X695822Y19166D01*
X695746Y18701D01*
X695631Y18391D01*
X695401Y18081D01*
X695132Y17874D01*
X694864Y17771D01*
X694596D01*
X694327Y17874D01*
X694097Y18029D01*
X693906Y18236D01*
G01X695469Y45012D02*
Y48112D01*
G01X693859D02*
Y45012D01*
G01Y46562D02*
X695469D01*
G01X694534Y41473D02*
X693767D01*
Y40543D01*
X693997Y40233D01*
X694266Y40026D01*
X694649Y39923D01*
X695032Y40026D01*
X695301Y40233D01*
X695531Y40543D01*
X695684Y40905D01*
X695761Y41318D01*
Y41680D01*
X695684Y41990D01*
X695531Y42351D01*
X695301Y42661D01*
X695071Y42868D01*
X694764Y43023D01*
X694496D01*
X694189Y42920D01*
X693959Y42713D01*
G01X695192Y34035D02*
Y37135D01*
X693736D01*
G01X694272Y35637D02*
X695192D01*
G01X694924Y53900D02*
X694004D01*
G01X694464D02*
Y50800D01*
G01X694924D02*
X694004D01*
G01X777812Y-334733D02*
X778412Y-333933D01*
X779112Y-333533D01*
X779912Y-333400D01*
X780912Y-333667D01*
X781612Y-334333D01*
X781812Y-335133D01*
X781712Y-335934D01*
X781312Y-336600D01*
X779312Y-337933D01*
X778412Y-338867D01*
X777812Y-340200D01*
X777612Y-341400D01*
X781812D01*
G01X787712Y-333400D02*
X786912Y-333667D01*
X786312Y-334333D01*
X785912Y-335133D01*
X785612Y-336200D01*
X785512Y-337400D01*
X785612Y-338600D01*
X785912Y-339667D01*
X786312Y-340467D01*
X786912Y-341133D01*
X787712Y-341400D01*
X788512Y-341133D01*
X789112Y-340467D01*
X789512Y-339667D01*
X789812Y-338600D01*
X789912Y-337400D01*
X789812Y-336200D01*
X789512Y-335133D01*
X789112Y-334333D01*
X788512Y-333667D01*
X787712Y-333400D01*
G01X795712Y-341400D02*
Y-333400D01*
X794512Y-335000D01*
G01Y-341400D02*
X796912D01*
G01X801812Y-334733D02*
X802412Y-333933D01*
X803112Y-333533D01*
X803912Y-333400D01*
X804912Y-333667D01*
X805612Y-334333D01*
X805812Y-335133D01*
X805712Y-335934D01*
X805312Y-336600D01*
X803312Y-337933D01*
X802412Y-338867D01*
X801812Y-340200D01*
X801612Y-341400D01*
X805812D01*
G01X809912Y-341667D02*
X813512Y-333400D01*
G01X819712Y-341400D02*
Y-333400D01*
X818512Y-335000D01*
G01Y-341400D02*
X820912D01*
G01X827712Y-333400D02*
X826912Y-333667D01*
X826312Y-334333D01*
X825912Y-335133D01*
X825612Y-336200D01*
X825512Y-337400D01*
X825612Y-338600D01*
X825912Y-339667D01*
X826312Y-340467D01*
X826912Y-341133D01*
X827712Y-341400D01*
X828512Y-341133D01*
X829112Y-340467D01*
X829512Y-339667D01*
X829812Y-338600D01*
X829912Y-337400D01*
X829812Y-336200D01*
X829512Y-335133D01*
X829112Y-334333D01*
X828512Y-333667D01*
X827712Y-333400D01*
G01X833912Y-341667D02*
X837512Y-333400D01*
G01X841512Y-339800D02*
X842112Y-340733D01*
X842912Y-341267D01*
X843812Y-341400D01*
X844612Y-341267D01*
X845412Y-340600D01*
X845912Y-339800D01*
X846012Y-339000D01*
X845812Y-338067D01*
X845112Y-337400D01*
X844412Y-337133D01*
X843512D01*
G01X844412D02*
X845012Y-336733D01*
X845512Y-336067D01*
X845712Y-335267D01*
X845512Y-334467D01*
X845012Y-333800D01*
X844112Y-333400D01*
X843212Y-333533D01*
X842312Y-334067D01*
G01X851712Y-341400D02*
Y-333400D01*
X850512Y-335000D01*
G01Y-341400D02*
X852912D01*
G01X777512Y-316400D02*
Y-308400D01*
X779512D01*
X780312Y-308800D01*
X780912Y-309333D01*
X781412Y-310133D01*
X781812Y-311067D01*
X781912Y-312400D01*
X781812Y-313733D01*
X781412Y-314667D01*
X780912Y-315467D01*
X780312Y-316000D01*
X779512Y-316400D01*
X777512D01*
G01X785212D02*
X787712Y-308400D01*
X790212Y-316400D01*
G01X789312Y-313600D02*
X786112D01*
G01X795712Y-308400D02*
X794912Y-308667D01*
X794312Y-309333D01*
X793912Y-310133D01*
X793612Y-311200D01*
X793512Y-312400D01*
X793612Y-313600D01*
X793912Y-314667D01*
X794312Y-315467D01*
X794912Y-316133D01*
X795712Y-316400D01*
X796512Y-316133D01*
X797112Y-315467D01*
X797512Y-314667D01*
X797812Y-313600D01*
X797912Y-312400D01*
X797812Y-311200D01*
X797512Y-310133D01*
X797112Y-309333D01*
X796512Y-308667D01*
X795712Y-308400D01*
G01X803712D02*
Y-316400D01*
G01X801412Y-308400D02*
X806012D01*
G01X809812Y-313067D02*
X810512Y-312133D01*
X811112Y-311600D01*
X811912Y-311333D01*
X812612Y-311600D01*
X813112Y-312133D01*
X813512Y-312933D01*
X813612Y-313867D01*
X813512Y-314667D01*
X813112Y-315467D01*
X812512Y-316133D01*
X811812Y-316400D01*
X811012Y-316133D01*
X810312Y-315334D01*
X809912Y-314133D01*
X809812Y-312800D01*
X810012Y-311067D01*
X810312Y-310133D01*
X810812Y-309200D01*
X811512Y-308533D01*
X812212Y-308400D01*
X812912Y-308667D01*
X813412Y-309333D01*
G01X817112Y-316400D02*
Y-308400D01*
X819712Y-315067D01*
X822312Y-308400D01*
Y-316400D01*
G01X827712Y-308400D02*
Y-316400D01*
G01X825412Y-308400D02*
X830012D01*
G01X833612Y-316400D02*
Y-308400D01*
G01X837812D02*
Y-316400D01*
G01Y-312400D02*
X833612D01*
G01X843712Y-316400D02*
X844412Y-316267D01*
X845212Y-315867D01*
X845712Y-315200D01*
X845912Y-314267D01*
X845712Y-313334D01*
X845112Y-312533D01*
X844212Y-312133D01*
X843212D01*
X842612Y-311867D01*
X842112Y-311200D01*
X841912Y-310267D01*
X842212Y-309333D01*
X842912Y-308667D01*
X843712Y-308400D01*
X844512Y-308667D01*
X845212Y-309333D01*
X845512Y-310267D01*
X845312Y-311200D01*
X844812Y-311867D01*
X844212Y-312133D01*
X843212D01*
X842312Y-312533D01*
X841712Y-313334D01*
X841512Y-314267D01*
X841712Y-315200D01*
X842212Y-315867D01*
X843012Y-316267D01*
X843712Y-316400D01*
G01X853912Y-309067D02*
X853312Y-308667D01*
X852612Y-308400D01*
X851812D01*
X850912Y-308800D01*
X850212Y-309467D01*
X849712Y-310267D01*
X849312Y-311600D01*
X849212Y-312800D01*
X849412Y-314000D01*
X849712Y-314800D01*
X850312Y-315600D01*
X851012Y-316133D01*
X851712Y-316400D01*
X852412D01*
X853112Y-316133D01*
X853712Y-315733D01*
X854212Y-315200D01*
G01X859712Y-308400D02*
X858912Y-308667D01*
X858312Y-309333D01*
X857912Y-310133D01*
X857612Y-311200D01*
X857512Y-312400D01*
X857612Y-313600D01*
X857912Y-314667D01*
X858312Y-315467D01*
X858912Y-316133D01*
X859712Y-316400D01*
X860512Y-316133D01*
X861112Y-315467D01*
X861512Y-314667D01*
X861812Y-313600D01*
X861912Y-312400D01*
X861812Y-311200D01*
X861512Y-310133D01*
X861112Y-309333D01*
X860512Y-308667D01*
X859712Y-308400D01*
G01X799712Y-283400D02*
Y-291400D01*
G01X797412Y-283400D02*
X802012D01*
G01X805812Y-288067D02*
X806512Y-287133D01*
X807112Y-286600D01*
X807912Y-286333D01*
X808612Y-286600D01*
X809112Y-287133D01*
X809512Y-287933D01*
X809612Y-288867D01*
X809512Y-289667D01*
X809112Y-290467D01*
X808512Y-291133D01*
X807812Y-291400D01*
X807012Y-291133D01*
X806312Y-290334D01*
X805912Y-289133D01*
X805812Y-287800D01*
X806012Y-286067D01*
X806312Y-285133D01*
X806812Y-284200D01*
X807512Y-283533D01*
X808212Y-283400D01*
X808912Y-283667D01*
X809412Y-284333D01*
G01X813112Y-291400D02*
Y-283400D01*
X815712Y-290067D01*
X818312Y-283400D01*
Y-291400D01*
G01X820712Y-294067D02*
X826712D01*
G01X831712Y-283400D02*
Y-291400D01*
G01X829412Y-283400D02*
X834012D01*
G01X838312Y-291400D02*
Y-286067D01*
G01Y-287133D02*
X838812Y-286600D01*
X839312Y-286200D01*
X840012Y-286067D01*
X840512Y-286200D01*
X841112Y-286600D01*
G01X849512Y-291400D02*
Y-286067D01*
G01Y-287000D02*
X849112Y-286467D01*
X848512Y-286200D01*
X847812Y-286067D01*
X847112Y-286333D01*
X846512Y-286867D01*
X846112Y-287667D01*
X845912Y-288733D01*
X846112Y-289800D01*
X846512Y-290600D01*
X847112Y-291133D01*
X847812Y-291400D01*
X848512Y-291267D01*
X849112Y-290867D01*
X849512Y-290334D01*
G01X853612Y-293800D02*
X854212Y-294067D01*
X855012Y-293800D01*
X855512Y-293267D01*
X855912Y-292600D01*
X856512Y-290467D01*
X857812Y-286067D01*
G01X854612D02*
X856512Y-290467D01*
G01X860712Y-294067D02*
X866712D01*
G01X872512Y-287133D02*
X872912Y-286733D01*
X873212Y-286067D01*
X873412Y-285133D01*
X873212Y-284333D01*
X872812Y-283800D01*
X872112Y-283400D01*
X869412D01*
Y-291400D01*
X872712D01*
X873412Y-290867D01*
X873812Y-290067D01*
X874012Y-289133D01*
X873812Y-288200D01*
X873212Y-287400D01*
X872512Y-287133D01*
X869412D01*
G01X877712Y-291400D02*
Y-283400D01*
X880112D01*
X880912Y-283800D01*
X881512Y-284733D01*
X881712Y-285800D01*
X881512Y-286867D01*
X881012Y-287667D01*
X880112Y-288067D01*
X877712D01*
G01X806008Y109138D02*
X805241D01*
Y108208D01*
X805471Y107898D01*
X805740Y107691D01*
X806123Y107588D01*
X806506Y107691D01*
X806775Y107898D01*
X807005Y108208D01*
X807158Y108570D01*
X807235Y108983D01*
Y109345D01*
X807158Y109655D01*
X807005Y110016D01*
X806775Y110326D01*
X806545Y110533D01*
X806238Y110688D01*
X805970D01*
X805663Y110585D01*
X805433Y110378D01*
G01X803866Y108880D02*
X803598Y109241D01*
X803368Y109448D01*
X803061Y109551D01*
X802793Y109448D01*
X802601Y109241D01*
X802448Y108931D01*
X802410Y108570D01*
X802448Y108260D01*
X802601Y107950D01*
X802831Y107691D01*
X803100Y107588D01*
X803406Y107691D01*
X803675Y108001D01*
X803828Y108466D01*
X803866Y108983D01*
X803790Y109655D01*
X803675Y110016D01*
X803483Y110378D01*
X803215Y110636D01*
X802946Y110688D01*
X802678Y110585D01*
X802486Y110326D01*
G01X801308Y132761D02*
X800541D01*
Y131831D01*
X800771Y131521D01*
X801040Y131314D01*
X801423Y131211D01*
X801806Y131314D01*
X802075Y131521D01*
X802305Y131831D01*
X802458Y132193D01*
X802535Y132606D01*
Y132968D01*
X802458Y133278D01*
X802305Y133639D01*
X802075Y133949D01*
X801845Y134156D01*
X801538Y134311D01*
X801270D01*
X800963Y134208D01*
X800733Y134001D01*
G01X799281Y131676D02*
X799051Y131418D01*
X798783Y131263D01*
X798438Y131211D01*
X798093Y131314D01*
X797825Y131521D01*
X797633Y131883D01*
X797595Y132296D01*
X797671Y132709D01*
X797863Y132968D01*
X798131Y133174D01*
X798400Y133226D01*
X798668Y133174D01*
X799013Y132968D01*
X798898Y134311D01*
X797863D01*
G01X805008Y168194D02*
X804241D01*
Y167264D01*
X804471Y166954D01*
X804740Y166747D01*
X805123Y166644D01*
X805506Y166747D01*
X805775Y166954D01*
X806005Y167264D01*
X806158Y167626D01*
X806235Y168039D01*
Y168401D01*
X806158Y168711D01*
X806005Y169072D01*
X805775Y169382D01*
X805545Y169589D01*
X805238Y169744D01*
X804970D01*
X804663Y169641D01*
X804433Y169434D01*
G01X801678Y166644D02*
Y169744D01*
X803096Y167522D01*
X801180D01*
G01X896912Y-334067D02*
X896312Y-333667D01*
X895612Y-333400D01*
X894812D01*
X893912Y-333800D01*
X893212Y-334467D01*
X892712Y-335267D01*
X892312Y-336600D01*
X892212Y-337800D01*
X892412Y-339000D01*
X892712Y-339800D01*
X893312Y-340600D01*
X894012Y-341133D01*
X894712Y-341400D01*
X895412D01*
X896112Y-341133D01*
X896712Y-340733D01*
X897212Y-340200D01*
G01X922212Y-341400D02*
Y-333400D01*
X921012Y-335000D01*
G01Y-341400D02*
X923412D01*
G01X928312Y-338067D02*
X929012Y-337133D01*
X929612Y-336600D01*
X930412Y-336333D01*
X931112Y-336600D01*
X931612Y-337133D01*
X932012Y-337933D01*
X932112Y-338867D01*
X932012Y-339667D01*
X931612Y-340467D01*
X931012Y-341133D01*
X930312Y-341400D01*
X929512Y-341133D01*
X928812Y-340334D01*
X928412Y-339133D01*
X928312Y-337800D01*
X928512Y-336067D01*
X928812Y-335133D01*
X929312Y-334200D01*
X930012Y-333533D01*
X930712Y-333400D01*
X931412Y-333667D01*
X931912Y-334333D01*
G01X1164101Y40283D02*
Y43383D01*
X1164561Y42763D01*
G01Y40283D02*
X1163641D01*
G01X1256870Y-52954D02*
X1186594D01*
G01D02*
Y86022D01*
G01X1202125Y18651D02*
Y21751D01*
X1201359D01*
X1201052Y21596D01*
X1200822Y21389D01*
X1200630Y21079D01*
X1200477Y20718D01*
X1200439Y20201D01*
X1200477Y19684D01*
X1200630Y19323D01*
X1200822Y19013D01*
X1201052Y18806D01*
X1201359Y18651D01*
X1202125D01*
G01X1198910Y21234D02*
X1198680Y21544D01*
X1198412Y21699D01*
X1198105Y21751D01*
X1197722Y21648D01*
X1197454Y21389D01*
X1197377Y21079D01*
X1197415Y20769D01*
X1197569Y20511D01*
X1198335Y19994D01*
X1198680Y19633D01*
X1198910Y19116D01*
X1198987Y18651D01*
X1197377D01*
G01X1202125Y10776D02*
Y13876D01*
X1201359D01*
X1201052Y13721D01*
X1200822Y13514D01*
X1200630Y13204D01*
X1200477Y12843D01*
X1200439Y12326D01*
X1200477Y11809D01*
X1200630Y11448D01*
X1200822Y11138D01*
X1201052Y10931D01*
X1201359Y10776D01*
X1202125D01*
G01X1199025Y11396D02*
X1198795Y11034D01*
X1198489Y10828D01*
X1198144Y10776D01*
X1197837Y10828D01*
X1197530Y11086D01*
X1197339Y11396D01*
X1197300Y11706D01*
X1197377Y12068D01*
X1197645Y12326D01*
X1197914Y12429D01*
X1198259D01*
G01X1197914D02*
X1197684Y12584D01*
X1197492Y12843D01*
X1197415Y13153D01*
X1197492Y13463D01*
X1197684Y13721D01*
X1198029Y13876D01*
X1198374Y13824D01*
X1198719Y13618D01*
G01X1202125Y26525D02*
Y29625D01*
X1201359D01*
X1201052Y29470D01*
X1200822Y29263D01*
X1200630Y28953D01*
X1200477Y28592D01*
X1200439Y28075D01*
X1200477Y27558D01*
X1200630Y27197D01*
X1200822Y26887D01*
X1201052Y26680D01*
X1201359Y26525D01*
X1202125D01*
G01X1198182D02*
Y29625D01*
X1198642Y29005D01*
G01Y26525D02*
X1197722D01*
G01X1202240Y42273D02*
X1201282Y45373D01*
X1200324Y42273D01*
G01X1200669Y43358D02*
X1201895D01*
G01X1199025Y42893D02*
X1198795Y42531D01*
X1198489Y42325D01*
X1198144Y42273D01*
X1197837Y42325D01*
X1197530Y42583D01*
X1197339Y42893D01*
X1197300Y43203D01*
X1197377Y43565D01*
X1197645Y43823D01*
X1197914Y43926D01*
X1198259D01*
G01X1197914D02*
X1197684Y44081D01*
X1197492Y44340D01*
X1197415Y44650D01*
X1197492Y44960D01*
X1197684Y45218D01*
X1198029Y45373D01*
X1198374Y45321D01*
X1198719Y45115D01*
G01X1202240Y50147D02*
X1201282Y53247D01*
X1200324Y50147D01*
G01X1200669Y51232D02*
X1201895D01*
G01X1198910Y52730D02*
X1198680Y53040D01*
X1198412Y53195D01*
X1198105Y53247D01*
X1197722Y53144D01*
X1197454Y52885D01*
X1197377Y52575D01*
X1197415Y52265D01*
X1197569Y52007D01*
X1198335Y51490D01*
X1198680Y51129D01*
X1198910Y50612D01*
X1198987Y50147D01*
X1197377D01*
G01X1202240Y58021D02*
X1201282Y61121D01*
X1200324Y58021D01*
G01X1200669Y59106D02*
X1201895D01*
G01X1198182Y58021D02*
Y61121D01*
X1198642Y60501D01*
G01Y58021D02*
X1197722D01*
G01X1249499Y77600D02*
Y83900D01*
X1247619D01*
X1246992Y83585D01*
X1246522Y82850D01*
X1246365Y82010D01*
X1246522Y81170D01*
X1246914Y80540D01*
X1247619Y80225D01*
X1249499D01*
G01X1243199Y77600D02*
Y83900D01*
X1241240D01*
X1240614Y83585D01*
X1240222Y83165D01*
X1240065Y82325D01*
X1240222Y81485D01*
X1240692Y80960D01*
X1241240Y80645D01*
X1243199D01*
G01X1241240D02*
X1240065Y77600D01*
G01X1233765D02*
X1236899D01*
Y83900D01*
X1233765D01*
G01X1235019Y80855D02*
X1236899D01*
G01X1230677Y78440D02*
X1230050Y77915D01*
X1229345Y77600D01*
X1228719D01*
X1228092Y77915D01*
X1227622Y78440D01*
X1227387Y79175D01*
X1227544Y79910D01*
X1227935Y80540D01*
X1228640Y80960D01*
X1229580Y81170D01*
X1230129Y81590D01*
X1230364Y82325D01*
X1230207Y83060D01*
X1229815Y83585D01*
X1229267Y83900D01*
X1228719D01*
X1228170Y83690D01*
X1227700Y83165D01*
G01X1224377Y78440D02*
X1223750Y77915D01*
X1223045Y77600D01*
X1222419D01*
X1221792Y77915D01*
X1221322Y78440D01*
X1221087Y79175D01*
X1221244Y79910D01*
X1221635Y80540D01*
X1222340Y80960D01*
X1223280Y81170D01*
X1223829Y81590D01*
X1224064Y82325D01*
X1223907Y83060D01*
X1223515Y83585D01*
X1222967Y83900D01*
X1222419D01*
X1221870Y83690D01*
X1221400Y83165D01*
G01X1217450Y79700D02*
X1215414D01*
G01X1211620Y77600D02*
Y83900D01*
X1208644D01*
G01X1209740Y80855D02*
X1211620D01*
G01X1204772Y83900D02*
X1202892D01*
G01X1203832D02*
Y77600D01*
G01X1204772D02*
X1202892D01*
G01X1197532Y83900D02*
Y77600D01*
G01X1199334Y83900D02*
X1195730D01*
G01X1186594Y86022D02*
X1256870D01*
G01X1244439Y21493D02*
X1244669Y21648D01*
X1244937Y21751D01*
X1245244D01*
X1245589Y21596D01*
X1245857Y21338D01*
X1246049Y21028D01*
X1246202Y20511D01*
X1246240Y20046D01*
X1246164Y19581D01*
X1246049Y19271D01*
X1245819Y18961D01*
X1245550Y18754D01*
X1245282Y18651D01*
X1245014D01*
X1244745Y18754D01*
X1244515Y18909D01*
X1244324Y19116D01*
G01X1242910Y21234D02*
X1242680Y21544D01*
X1242412Y21699D01*
X1242105Y21751D01*
X1241722Y21648D01*
X1241454Y21389D01*
X1241377Y21079D01*
X1241415Y20769D01*
X1241569Y20511D01*
X1242335Y19994D01*
X1242680Y19633D01*
X1242910Y19116D01*
X1242987Y18651D01*
X1241377D01*
G01X1244439Y13618D02*
X1244669Y13773D01*
X1244937Y13876D01*
X1245244D01*
X1245589Y13721D01*
X1245857Y13463D01*
X1246049Y13153D01*
X1246202Y12636D01*
X1246240Y12171D01*
X1246164Y11706D01*
X1246049Y11396D01*
X1245819Y11086D01*
X1245550Y10879D01*
X1245282Y10776D01*
X1245014D01*
X1244745Y10879D01*
X1244515Y11034D01*
X1244324Y11241D01*
G01X1243025Y11396D02*
X1242795Y11034D01*
X1242489Y10828D01*
X1242144Y10776D01*
X1241837Y10828D01*
X1241530Y11086D01*
X1241339Y11396D01*
X1241300Y11706D01*
X1241377Y12068D01*
X1241645Y12326D01*
X1241914Y12429D01*
X1242259D01*
G01X1241914D02*
X1241684Y12584D01*
X1241492Y12843D01*
X1241415Y13153D01*
X1241492Y13463D01*
X1241684Y13721D01*
X1242029Y13876D01*
X1242374Y13824D01*
X1242719Y13618D01*
G01X1244439Y29367D02*
X1244669Y29522D01*
X1244937Y29625D01*
X1245244D01*
X1245589Y29470D01*
X1245857Y29212D01*
X1246049Y28902D01*
X1246202Y28385D01*
X1246240Y27920D01*
X1246164Y27455D01*
X1246049Y27145D01*
X1245819Y26835D01*
X1245550Y26628D01*
X1245282Y26525D01*
X1245014D01*
X1244745Y26628D01*
X1244515Y26783D01*
X1244324Y26990D01*
G01X1242182Y26525D02*
Y29625D01*
X1242642Y29005D01*
G01Y26525D02*
X1241722D01*
G01X1325571Y23200D02*
Y17698D01*
X1237973D01*
G01D02*
Y125900D01*
G01X1244975Y51800D02*
X1244822Y51955D01*
X1244707Y52214D01*
X1244630Y52575D01*
X1244707Y52885D01*
X1244860Y53092D01*
X1245129Y53247D01*
X1246164D01*
Y50147D01*
X1244899D01*
X1244630Y50354D01*
X1244477Y50664D01*
X1244400Y51025D01*
X1244477Y51387D01*
X1244707Y51697D01*
X1244975Y51800D01*
X1246164D01*
G01X1242910Y52730D02*
X1242680Y53040D01*
X1242412Y53195D01*
X1242105Y53247D01*
X1241722Y53144D01*
X1241454Y52885D01*
X1241377Y52575D01*
X1241415Y52265D01*
X1241569Y52007D01*
X1242335Y51490D01*
X1242680Y51129D01*
X1242910Y50612D01*
X1242987Y50147D01*
X1241377D01*
G01X1244975Y43926D02*
X1244822Y44081D01*
X1244707Y44340D01*
X1244630Y44701D01*
X1244707Y45011D01*
X1244860Y45218D01*
X1245129Y45373D01*
X1246164D01*
Y42273D01*
X1244899D01*
X1244630Y42480D01*
X1244477Y42790D01*
X1244400Y43151D01*
X1244477Y43513D01*
X1244707Y43823D01*
X1244975Y43926D01*
X1246164D01*
G01X1243025Y42893D02*
X1242795Y42531D01*
X1242489Y42325D01*
X1242144Y42273D01*
X1241837Y42325D01*
X1241530Y42583D01*
X1241339Y42893D01*
X1241300Y43203D01*
X1241377Y43565D01*
X1241645Y43823D01*
X1241914Y43926D01*
X1242259D01*
G01X1241914D02*
X1241684Y44081D01*
X1241492Y44340D01*
X1241415Y44650D01*
X1241492Y44960D01*
X1241684Y45218D01*
X1242029Y45373D01*
X1242374Y45321D01*
X1242719Y45115D01*
G01X1244975Y59674D02*
X1244822Y59829D01*
X1244707Y60088D01*
X1244630Y60449D01*
X1244707Y60759D01*
X1244860Y60966D01*
X1245129Y61121D01*
X1246164D01*
Y58021D01*
X1244899D01*
X1244630Y58228D01*
X1244477Y58538D01*
X1244400Y58899D01*
X1244477Y59261D01*
X1244707Y59571D01*
X1244975Y59674D01*
X1246164D01*
G01X1242182Y58021D02*
Y61121D01*
X1242642Y60501D01*
G01Y58021D02*
X1241722D01*
G01X1240377Y108439D02*
X1246677D01*
Y110319D01*
X1246362Y110946D01*
X1245627Y111416D01*
X1244787Y111573D01*
X1243947Y111416D01*
X1243317Y111024D01*
X1243002Y110319D01*
Y108439D01*
G01X1240377Y114739D02*
X1246677D01*
Y116698D01*
X1246362Y117324D01*
X1245942Y117716D01*
X1245102Y117873D01*
X1244262Y117716D01*
X1243737Y117246D01*
X1243422Y116698D01*
Y114739D01*
G01Y116698D02*
X1240377Y117873D01*
G01Y124173D02*
Y121039D01*
X1246677D01*
Y124173D01*
G01X1243632Y122919D02*
Y121039D01*
G01X1241217Y127261D02*
X1240692Y127888D01*
X1240377Y128593D01*
Y129219D01*
X1240692Y129846D01*
X1241217Y130316D01*
X1241952Y130551D01*
X1242687Y130394D01*
X1243317Y130003D01*
X1243737Y129298D01*
X1243947Y128358D01*
X1244367Y127809D01*
X1245102Y127574D01*
X1245837Y127731D01*
X1246362Y128123D01*
X1246677Y128671D01*
Y129219D01*
X1246467Y129768D01*
X1245942Y130238D01*
G01X1241217Y133561D02*
X1240692Y134188D01*
X1240377Y134893D01*
Y135519D01*
X1240692Y136146D01*
X1241217Y136616D01*
X1241952Y136851D01*
X1242687Y136694D01*
X1243317Y136303D01*
X1243737Y135598D01*
X1243947Y134658D01*
X1244367Y134109D01*
X1245102Y133874D01*
X1245837Y134031D01*
X1246362Y134423D01*
X1246677Y134971D01*
Y135519D01*
X1246467Y136068D01*
X1245942Y136538D01*
G01X1242477Y140488D02*
Y142524D01*
G01X1240377Y146318D02*
X1246677D01*
Y149294D01*
G01X1243632Y148198D02*
Y146318D01*
G01X1246677Y153166D02*
Y155046D01*
G01Y154106D02*
X1240377D01*
G01Y153166D02*
Y155046D01*
G01X1246677Y160406D02*
X1240377D01*
G01X1246677Y158604D02*
Y162208D01*
G01X1237973Y130000D02*
Y235414D01*
X1325571D01*
Y51700D01*
G01X1256870Y86022D02*
Y-52954D01*
G01X1320985Y-49508D02*
X1391851D01*
Y14100D01*
G01X1320985Y22100D02*
Y-49508D01*
G01X1325571Y39900D02*
Y29500D01*
G01X1320985Y35400D02*
Y29500D01*
G01X1325571Y39900D02*
Y46571D01*
G01X1391851Y63400D02*
Y80611D01*
X1320985D01*
Y50700D01*
G01X1383099Y71933D02*
Y78233D01*
X1381219D01*
X1380592Y77918D01*
X1380122Y77183D01*
X1379965Y76343D01*
X1380122Y75503D01*
X1380514Y74873D01*
X1381219Y74558D01*
X1383099D01*
G01X1376799Y71933D02*
Y78233D01*
X1374840D01*
X1374214Y77918D01*
X1373822Y77498D01*
X1373665Y76658D01*
X1373822Y75818D01*
X1374292Y75293D01*
X1374840Y74978D01*
X1376799D01*
G01X1374840D02*
X1373665Y71933D01*
G01X1367365D02*
X1370499D01*
Y78233D01*
X1367365D01*
G01X1368619Y75188D02*
X1370499D01*
G01X1364277Y72773D02*
X1363650Y72248D01*
X1362945Y71933D01*
X1362319D01*
X1361692Y72248D01*
X1361222Y72773D01*
X1360987Y73508D01*
X1361144Y74243D01*
X1361535Y74873D01*
X1362240Y75293D01*
X1363180Y75503D01*
X1363729Y75923D01*
X1363964Y76658D01*
X1363807Y77393D01*
X1363415Y77918D01*
X1362867Y78233D01*
X1362319D01*
X1361770Y78023D01*
X1361300Y77498D01*
G01X1357977Y72773D02*
X1357350Y72248D01*
X1356645Y71933D01*
X1356019D01*
X1355392Y72248D01*
X1354922Y72773D01*
X1354687Y73508D01*
X1354844Y74243D01*
X1355235Y74873D01*
X1355940Y75293D01*
X1356880Y75503D01*
X1357429Y75923D01*
X1357664Y76658D01*
X1357507Y77393D01*
X1357115Y77918D01*
X1356567Y78233D01*
X1356019D01*
X1355470Y78023D01*
X1355000Y77498D01*
G01X1351050Y74033D02*
X1349014D01*
G01X1345220Y71933D02*
Y78233D01*
X1342244D01*
G01X1343340Y75188D02*
X1345220D01*
G01X1338372Y78233D02*
X1336492D01*
G01X1337432D02*
Y71933D01*
G01X1338372D02*
X1336492D01*
G01X1331132Y78233D02*
Y71933D01*
G01X1332934Y78233D02*
X1329330D01*
G01X1333227Y115854D02*
X1333074Y116009D01*
X1332959Y116268D01*
X1332882Y116629D01*
X1332959Y116939D01*
X1333112Y117146D01*
X1333381Y117301D01*
X1334416D01*
Y114201D01*
X1333151D01*
X1332882Y114408D01*
X1332729Y114718D01*
X1332652Y115079D01*
X1332729Y115441D01*
X1332959Y115751D01*
X1333227Y115854D01*
X1334416D01*
G01X1330434Y114201D02*
Y117301D01*
X1330894Y116681D01*
G01Y114201D02*
X1329974D01*
G01X1334192Y140216D02*
X1333234Y143316D01*
X1332276Y140216D01*
G01X1332621Y141301D02*
X1333847D01*
G01X1330134Y140216D02*
X1329866Y140268D01*
X1329559Y140423D01*
X1329367Y140681D01*
X1329291Y141043D01*
X1329367Y141404D01*
X1329597Y141714D01*
X1329942Y141869D01*
X1330326D01*
X1330556Y141973D01*
X1330747Y142231D01*
X1330824Y142593D01*
X1330709Y142954D01*
X1330441Y143213D01*
X1330134Y143316D01*
X1329827Y143213D01*
X1329559Y142954D01*
X1329444Y142593D01*
X1329521Y142231D01*
X1329712Y141973D01*
X1329942Y141869D01*
X1330326D01*
X1330671Y141714D01*
X1330901Y141404D01*
X1330977Y141043D01*
X1330901Y140681D01*
X1330709Y140423D01*
X1330402Y140268D01*
X1330134Y140216D01*
G01X1336490Y125654D02*
X1336337Y125809D01*
X1336222Y126068D01*
X1336145Y126429D01*
X1336222Y126739D01*
X1336375Y126946D01*
X1336644Y127101D01*
X1337679D01*
Y124001D01*
X1336414D01*
X1336145Y124208D01*
X1335992Y124518D01*
X1335915Y124879D01*
X1335992Y125241D01*
X1336222Y125551D01*
X1336490Y125654D01*
X1337679D01*
G01X1334425Y126584D02*
X1334195Y126894D01*
X1333927Y127049D01*
X1333620Y127101D01*
X1333237Y126998D01*
X1332969Y126739D01*
X1332892Y126429D01*
X1332930Y126119D01*
X1333084Y125861D01*
X1333850Y125344D01*
X1334195Y124983D01*
X1334425Y124466D01*
X1334502Y124001D01*
X1332892D01*
G01X1338655Y149705D02*
X1337697Y152805D01*
X1336739Y149705D01*
G01X1337084Y150790D02*
X1338310D01*
G01X1334674Y149705D02*
X1334597Y150377D01*
X1334482Y150945D01*
X1334329Y151462D01*
X1334137Y152030D01*
X1333830Y152805D01*
X1335364D01*
G01X1383725Y6399D02*
X1382767Y9499D01*
X1381809Y6399D01*
G01X1382154Y7484D02*
X1383380D01*
G01X1387264Y25100D02*
Y29900D01*
G01Y22100D02*
Y25100D01*
G01X1380337Y29847D02*
X1381871D01*
Y32947D01*
X1380337D01*
G01X1380951Y31449D02*
X1381871D01*
G01X1381697Y13636D02*
X1381544Y13791D01*
X1381429Y14050D01*
X1381352Y14411D01*
X1381429Y14721D01*
X1381582Y14928D01*
X1381851Y15083D01*
X1382886D01*
Y11983D01*
X1381621D01*
X1381352Y12190D01*
X1381199Y12500D01*
X1381122Y12861D01*
X1381199Y13223D01*
X1381429Y13533D01*
X1381697Y13636D01*
X1382886D01*
G01X1385447Y23159D02*
Y26259D01*
X1384681D01*
X1384374Y26104D01*
X1384144Y25897D01*
X1383952Y25587D01*
X1383799Y25226D01*
X1383761Y24709D01*
X1383799Y24192D01*
X1383952Y23831D01*
X1384144Y23521D01*
X1384374Y23314D01*
X1384681Y23159D01*
X1385447D01*
G01X1378661Y17813D02*
X1378891Y17968D01*
X1379159Y18071D01*
X1379466D01*
X1379811Y17916D01*
X1380079Y17658D01*
X1380271Y17348D01*
X1380424Y16831D01*
X1380462Y16366D01*
X1380386Y15901D01*
X1380271Y15591D01*
X1380041Y15281D01*
X1379772Y15074D01*
X1379504Y14971D01*
X1379236D01*
X1378967Y15074D01*
X1378737Y15229D01*
X1378546Y15436D01*
G01X1387264Y46800D02*
Y85500D01*
G01X1381291Y49788D02*
Y46688D01*
G01X1382901D02*
Y49788D01*
G01Y48238D02*
X1381291D01*
G01X1381174Y39173D02*
X1380407D01*
Y38243D01*
X1380637Y37933D01*
X1380906Y37726D01*
X1381289Y37623D01*
X1381672Y37726D01*
X1381941Y37933D01*
X1382171Y38243D01*
X1382324Y38605D01*
X1382401Y39018D01*
Y39380D01*
X1382324Y39690D01*
X1382171Y40051D01*
X1381941Y40361D01*
X1381711Y40568D01*
X1381404Y40723D01*
X1381136D01*
X1380829Y40620D01*
X1380599Y40413D01*
G01X1381832Y33735D02*
Y36835D01*
X1380376D01*
G01X1380912Y35337D02*
X1381832D01*
G01X1381636Y52200D02*
X1382556D01*
G01X1382096D02*
Y55300D01*
G01X1381636D02*
X1382556D01*
G01X1387264Y89300D02*
Y235414D01*
X1474862D01*
Y17698D01*
X1393400D01*
G01X1377320Y115154D02*
X1377167Y115309D01*
X1377052Y115568D01*
X1376975Y115929D01*
X1377052Y116239D01*
X1377205Y116446D01*
X1377474Y116601D01*
X1378509D01*
Y113501D01*
X1377244D01*
X1376975Y113708D01*
X1376822Y114018D01*
X1376745Y114379D01*
X1376822Y114741D01*
X1377052Y115051D01*
X1377320Y115154D01*
X1378509D01*
G01X1374604Y113501D02*
X1374527Y114173D01*
X1374412Y114741D01*
X1374259Y115258D01*
X1374067Y115826D01*
X1373760Y116601D01*
X1375294D01*
G01X1378285Y140392D02*
X1377327Y143492D01*
X1376369Y140392D01*
G01X1376714Y141477D02*
X1377940D01*
G01X1374955Y142975D02*
X1374725Y143285D01*
X1374457Y143440D01*
X1374150Y143492D01*
X1373767Y143389D01*
X1373499Y143130D01*
X1373422Y142820D01*
X1373460Y142510D01*
X1373614Y142252D01*
X1374380Y141735D01*
X1374725Y141374D01*
X1374955Y140857D01*
X1375032Y140392D01*
X1373422D01*
G01X1381683Y125954D02*
X1381530Y126109D01*
X1381415Y126368D01*
X1381338Y126729D01*
X1381415Y127039D01*
X1381568Y127246D01*
X1381837Y127401D01*
X1382872D01*
Y124301D01*
X1381607D01*
X1381338Y124508D01*
X1381185Y124818D01*
X1381108Y125179D01*
X1381185Y125541D01*
X1381415Y125851D01*
X1381683Y125954D01*
X1382872D01*
G01X1378890Y124301D02*
X1378622Y124353D01*
X1378315Y124508D01*
X1378123Y124766D01*
X1378047Y125128D01*
X1378123Y125489D01*
X1378353Y125799D01*
X1378698Y125954D01*
X1379082D01*
X1379312Y126058D01*
X1379503Y126316D01*
X1379580Y126678D01*
X1379465Y127039D01*
X1379197Y127298D01*
X1378890Y127401D01*
X1378583Y127298D01*
X1378315Y127039D01*
X1378200Y126678D01*
X1378277Y126316D01*
X1378468Y126058D01*
X1378698Y125954D01*
X1379082D01*
X1379427Y125799D01*
X1379657Y125489D01*
X1379733Y125128D01*
X1379657Y124766D01*
X1379465Y124508D01*
X1379158Y124353D01*
X1378890Y124301D01*
G01X1383448Y150416D02*
X1382490Y153516D01*
X1381532Y150416D01*
G01X1381877Y151501D02*
X1383103D01*
G01X1379390Y150416D02*
Y153516D01*
X1379850Y152896D01*
G01Y150416D02*
X1378930D01*
G01X1391851Y25100D02*
Y30451D01*
G01Y22100D02*
Y25100D01*
G01Y43900D02*
Y63400D01*
G01Y38800D02*
Y43900D01*
G01X1469376Y40283D02*
Y43383D01*
X1469836Y42763D01*
G01Y40283D02*
X1468916D01*
G01X1464986Y100839D02*
X1471286D01*
Y102719D01*
X1470971Y103346D01*
X1470236Y103816D01*
X1469396Y103973D01*
X1468556Y103816D01*
X1467926Y103424D01*
X1467611Y102719D01*
Y100839D01*
G01X1464986Y107139D02*
X1471286D01*
Y109098D01*
X1470971Y109724D01*
X1470551Y110116D01*
X1469711Y110273D01*
X1468871Y110116D01*
X1468346Y109646D01*
X1468031Y109098D01*
Y107139D01*
G01Y109098D02*
X1464986Y110273D01*
G01Y116573D02*
Y113439D01*
X1471286D01*
Y116573D01*
G01X1468241Y115319D02*
Y113439D01*
G01X1465826Y119661D02*
X1465301Y120288D01*
X1464986Y120993D01*
Y121619D01*
X1465301Y122246D01*
X1465826Y122716D01*
X1466561Y122951D01*
X1467296Y122794D01*
X1467926Y122403D01*
X1468346Y121698D01*
X1468556Y120758D01*
X1468976Y120209D01*
X1469711Y119974D01*
X1470446Y120131D01*
X1470971Y120523D01*
X1471286Y121071D01*
Y121619D01*
X1471076Y122168D01*
X1470551Y122638D01*
G01X1465826Y125961D02*
X1465301Y126588D01*
X1464986Y127293D01*
Y127919D01*
X1465301Y128546D01*
X1465826Y129016D01*
X1466561Y129251D01*
X1467296Y129094D01*
X1467926Y128703D01*
X1468346Y127998D01*
X1468556Y127058D01*
X1468976Y126509D01*
X1469711Y126274D01*
X1470446Y126431D01*
X1470971Y126823D01*
X1471286Y127371D01*
Y127919D01*
X1471076Y128468D01*
X1470551Y128938D01*
G01X1467086Y132888D02*
Y134924D01*
G01X1464986Y138718D02*
X1471286D01*
Y141694D01*
G01X1468241Y140598D02*
Y138718D01*
G01X1471286Y145566D02*
Y147446D01*
G01Y146506D02*
X1464986D01*
G01Y145566D02*
Y147446D01*
G01X1471286Y152806D02*
X1464986D01*
G01X1471286Y151004D02*
Y154608D01*
G01X1503504Y-49508D02*
X1574370D01*
Y80611D01*
X1503504D01*
Y-49508D01*
G01X1505552Y8901D02*
X1511852D01*
Y10781D01*
X1511537Y11408D01*
X1510802Y11878D01*
X1509962Y12035D01*
X1509122Y11878D01*
X1508492Y11486D01*
X1508177Y10781D01*
Y8901D01*
G01X1505552Y15201D02*
X1511852D01*
Y17160D01*
X1511537Y17786D01*
X1511117Y18178D01*
X1510277Y18335D01*
X1509437Y18178D01*
X1508912Y17708D01*
X1508597Y17160D01*
Y15201D01*
G01Y17160D02*
X1505552Y18335D01*
G01Y24635D02*
Y21501D01*
X1511852D01*
Y24635D01*
G01X1508807Y23381D02*
Y21501D01*
G01X1506392Y27723D02*
X1505867Y28350D01*
X1505552Y29055D01*
Y29681D01*
X1505867Y30308D01*
X1506392Y30778D01*
X1507127Y31013D01*
X1507862Y30856D01*
X1508492Y30465D01*
X1508912Y29760D01*
X1509122Y28820D01*
X1509542Y28271D01*
X1510277Y28036D01*
X1511012Y28193D01*
X1511537Y28585D01*
X1511852Y29133D01*
Y29681D01*
X1511642Y30230D01*
X1511117Y30700D01*
G01X1506392Y34023D02*
X1505867Y34650D01*
X1505552Y35355D01*
Y35981D01*
X1505867Y36608D01*
X1506392Y37078D01*
X1507127Y37313D01*
X1507862Y37156D01*
X1508492Y36765D01*
X1508912Y36060D01*
X1509122Y35120D01*
X1509542Y34571D01*
X1510277Y34336D01*
X1511012Y34493D01*
X1511537Y34885D01*
X1511852Y35433D01*
Y35981D01*
X1511642Y36530D01*
X1511117Y37000D01*
G01X1507652Y40950D02*
Y42986D01*
G01X1505552Y46780D02*
X1511852D01*
Y49756D01*
G01X1508807Y48660D02*
Y46780D01*
G01X1511852Y53628D02*
Y55508D01*
G01Y54568D02*
X1505552D01*
G01Y53628D02*
Y55508D01*
G01X1511852Y60868D02*
X1505552D01*
G01X1511852Y59066D02*
Y62670D01*
G01X1500487Y109138D02*
X1499720D01*
Y108208D01*
X1499950Y107898D01*
X1500219Y107691D01*
X1500602Y107588D01*
X1500985Y107691D01*
X1501254Y107898D01*
X1501484Y108208D01*
X1501637Y108570D01*
X1501714Y108983D01*
Y109345D01*
X1501637Y109655D01*
X1501484Y110016D01*
X1501254Y110326D01*
X1501024Y110533D01*
X1500717Y110688D01*
X1500449D01*
X1500142Y110585D01*
X1499912Y110378D01*
G01X1498460Y108208D02*
X1498230Y107846D01*
X1497924Y107640D01*
X1497579Y107588D01*
X1497272Y107640D01*
X1496965Y107898D01*
X1496774Y108208D01*
X1496735Y108518D01*
X1496812Y108880D01*
X1497080Y109138D01*
X1497349Y109241D01*
X1497694D01*
G01X1497349D02*
X1497119Y109396D01*
X1496927Y109655D01*
X1496850Y109965D01*
X1496927Y110275D01*
X1497119Y110533D01*
X1497464Y110688D01*
X1497809Y110636D01*
X1498154Y110430D01*
G01X1504787Y132761D02*
X1504020D01*
Y131831D01*
X1504250Y131521D01*
X1504519Y131314D01*
X1504902Y131211D01*
X1505285Y131314D01*
X1505554Y131521D01*
X1505784Y131831D01*
X1505937Y132193D01*
X1506014Y132606D01*
Y132968D01*
X1505937Y133278D01*
X1505784Y133639D01*
X1505554Y133949D01*
X1505324Y134156D01*
X1505017Y134311D01*
X1504749D01*
X1504442Y134208D01*
X1504212Y134001D01*
G01X1502645Y133794D02*
X1502415Y134104D01*
X1502147Y134259D01*
X1501840Y134311D01*
X1501457Y134208D01*
X1501189Y133949D01*
X1501112Y133639D01*
X1501150Y133329D01*
X1501304Y133071D01*
X1502070Y132554D01*
X1502415Y132193D01*
X1502645Y131676D01*
X1502722Y131211D01*
X1501112D01*
G01X1500387Y168261D02*
X1499620D01*
Y167331D01*
X1499850Y167021D01*
X1500119Y166814D01*
X1500502Y166711D01*
X1500885Y166814D01*
X1501154Y167021D01*
X1501384Y167331D01*
X1501537Y167693D01*
X1501614Y168106D01*
Y168468D01*
X1501537Y168778D01*
X1501384Y169139D01*
X1501154Y169449D01*
X1500924Y169656D01*
X1500617Y169811D01*
X1500349D01*
X1500042Y169708D01*
X1499812Y169501D01*
G01X1497517Y166711D02*
Y169811D01*
X1497977Y169191D01*
G01Y166711D02*
X1497057D01*
G01X1519976Y3291D02*
X1519708Y3652D01*
X1519478Y3859D01*
X1519171Y3962D01*
X1518903Y3859D01*
X1518711Y3652D01*
X1518558Y3342D01*
X1518520Y2981D01*
X1518558Y2671D01*
X1518711Y2361D01*
X1518941Y2102D01*
X1519210Y1999D01*
X1519516Y2102D01*
X1519785Y2412D01*
X1519938Y2877D01*
X1519976Y3394D01*
X1519900Y4066D01*
X1519785Y4427D01*
X1519593Y4789D01*
X1519325Y5047D01*
X1519056Y5099D01*
X1518788Y4996D01*
X1518596Y4737D01*
G01X1527891Y2364D02*
X1527661Y2106D01*
X1527393Y1951D01*
X1527048Y1899D01*
X1526703Y2002D01*
X1526435Y2209D01*
X1526243Y2571D01*
X1526205Y2984D01*
X1526281Y3397D01*
X1526473Y3656D01*
X1526741Y3862D01*
X1527010Y3914D01*
X1527278Y3862D01*
X1527623Y3656D01*
X1527508Y4999D01*
X1526473D01*
G01X1534788Y1899D02*
Y4999D01*
X1536206Y2777D01*
X1534290D01*
G01X1551376Y4582D02*
X1551146Y4892D01*
X1550878Y5047D01*
X1550571Y5099D01*
X1550188Y4996D01*
X1549920Y4737D01*
X1549843Y4427D01*
X1549881Y4117D01*
X1550035Y3859D01*
X1550801Y3342D01*
X1551146Y2981D01*
X1551376Y2464D01*
X1551453Y1999D01*
X1549843D01*
G01X1545591Y2419D02*
X1545361Y2057D01*
X1545055Y1851D01*
X1544710Y1799D01*
X1544403Y1851D01*
X1544096Y2109D01*
X1543905Y2419D01*
X1543866Y2729D01*
X1543943Y3091D01*
X1544211Y3349D01*
X1544480Y3452D01*
X1544825D01*
G01X1544480D02*
X1544250Y3607D01*
X1544058Y3866D01*
X1543981Y4176D01*
X1544058Y4486D01*
X1544250Y4744D01*
X1544595Y4899D01*
X1544940Y4847D01*
X1545285Y4641D01*
G01X1565506Y6599D02*
X1564548Y9699D01*
X1563590Y6599D01*
G01X1563935Y7684D02*
X1565161D01*
G01X1558848Y1699D02*
Y4799D01*
X1559308Y4179D01*
G01Y1699D02*
X1558388D01*
G01X1563618Y29047D02*
X1565152D01*
Y32147D01*
X1563618D01*
G01X1564232Y30649D02*
X1565152D01*
G01X1564078Y13936D02*
X1563925Y14091D01*
X1563810Y14350D01*
X1563733Y14711D01*
X1563810Y15021D01*
X1563963Y15228D01*
X1564232Y15383D01*
X1565267D01*
Y12283D01*
X1564002D01*
X1563733Y12490D01*
X1563580Y12800D01*
X1563503Y13161D01*
X1563580Y13523D01*
X1563810Y13833D01*
X1564078Y13936D01*
X1565267D01*
G01X1565228Y23359D02*
Y26459D01*
X1564462D01*
X1564155Y26304D01*
X1563925Y26097D01*
X1563733Y25787D01*
X1563580Y25426D01*
X1563542Y24909D01*
X1563580Y24392D01*
X1563733Y24031D01*
X1563925Y23721D01*
X1564155Y23514D01*
X1564462Y23359D01*
X1565228D01*
G01X1563642Y21013D02*
X1563872Y21168D01*
X1564140Y21271D01*
X1564447D01*
X1564792Y21116D01*
X1565060Y20858D01*
X1565252Y20548D01*
X1565405Y20031D01*
X1565443Y19566D01*
X1565367Y19101D01*
X1565252Y18791D01*
X1565022Y18481D01*
X1564753Y18274D01*
X1564485Y18171D01*
X1564217D01*
X1563948Y18274D01*
X1563718Y18429D01*
X1563527Y18636D01*
G01X1565290Y45012D02*
Y48112D01*
G01X1563680D02*
Y45012D01*
G01Y46562D02*
X1565290D01*
G01X1564455Y41273D02*
X1563688D01*
Y40343D01*
X1563918Y40033D01*
X1564187Y39826D01*
X1564570Y39723D01*
X1564953Y39826D01*
X1565222Y40033D01*
X1565452Y40343D01*
X1565605Y40705D01*
X1565682Y41118D01*
Y41480D01*
X1565605Y41790D01*
X1565452Y42151D01*
X1565222Y42461D01*
X1564992Y42668D01*
X1564685Y42823D01*
X1564417D01*
X1564110Y42720D01*
X1563880Y42513D01*
G01X1565113Y34335D02*
Y37435D01*
X1563657D01*
G01X1564193Y35937D02*
X1565113D01*
G01X1565145Y53500D02*
X1564225D01*
G01X1564685D02*
Y50400D01*
G01X1565145D02*
X1564225D01*
G01X1727612Y18504D02*
G03I-57100J0D01*
G01X1639016D02*
G03X1688714Y44208I31496J0D01*
G01X1652310D02*
G03X1639016Y18504I18202J-25704D01*
G01X1669187Y98638D02*
X1668420D01*
Y97708D01*
X1668650Y97398D01*
X1668919Y97191D01*
X1669302Y97088D01*
X1669685Y97191D01*
X1669954Y97398D01*
X1670184Y97708D01*
X1670337Y98070D01*
X1670414Y98483D01*
Y98845D01*
X1670337Y99155D01*
X1670184Y99516D01*
X1669954Y99826D01*
X1669724Y100033D01*
X1669417Y100188D01*
X1669149D01*
X1668842Y100085D01*
X1668612Y99878D01*
G01X1667045Y98380D02*
X1666777Y98741D01*
X1666547Y98948D01*
X1666240Y99051D01*
X1665972Y98948D01*
X1665780Y98741D01*
X1665627Y98431D01*
X1665589Y98070D01*
X1665627Y97760D01*
X1665780Y97450D01*
X1666010Y97191D01*
X1666279Y97088D01*
X1666585Y97191D01*
X1666854Y97501D01*
X1667007Y97966D01*
X1667045Y98483D01*
X1666969Y99155D01*
X1666854Y99516D01*
X1666662Y99878D01*
X1666394Y100136D01*
X1666125Y100188D01*
X1665857Y100085D01*
X1665665Y99826D01*
G01X1662626Y79194D02*
Y79961D01*
X1661696D01*
X1661386Y79731D01*
X1661179Y79462D01*
X1661076Y79079D01*
X1661179Y78696D01*
X1661386Y78427D01*
X1661696Y78197D01*
X1662058Y78044D01*
X1662471Y77967D01*
X1662833D01*
X1663143Y78044D01*
X1663504Y78197D01*
X1663814Y78427D01*
X1664021Y78657D01*
X1664176Y78964D01*
Y79232D01*
X1664073Y79539D01*
X1663866Y79769D01*
G01X1661076Y81182D02*
X1664176D01*
X1661076Y82946D01*
X1664176D01*
G01X1661076Y84321D02*
X1664176D01*
Y85087D01*
X1664021Y85394D01*
X1663814Y85624D01*
X1663504Y85816D01*
X1663143Y85969D01*
X1662626Y86007D01*
X1662109Y85969D01*
X1661748Y85816D01*
X1661438Y85624D01*
X1661231Y85394D01*
X1661076Y85087D01*
Y84321D01*
G01Y87497D02*
X1664176D01*
Y88417D01*
X1664021Y88724D01*
X1663659Y88954D01*
X1663246Y89031D01*
X1662833Y88954D01*
X1662523Y88762D01*
X1662368Y88417D01*
Y87497D01*
G01X1661076Y90406D02*
X1664176Y91364D01*
X1661076Y92322D01*
G01X1662161Y91977D02*
Y90751D01*
G01X1661076Y93621D02*
X1664176D01*
Y94387D01*
X1664021Y94694D01*
X1663814Y94924D01*
X1663504Y95116D01*
X1663143Y95269D01*
X1662626Y95307D01*
X1662109Y95269D01*
X1661748Y95116D01*
X1661438Y94924D01*
X1661231Y94694D01*
X1661076Y94387D01*
Y93621D01*
G01X1663659Y96836D02*
X1663969Y97066D01*
X1664124Y97334D01*
X1664176Y97641D01*
X1664073Y98024D01*
X1663814Y98292D01*
X1663504Y98369D01*
X1663194Y98331D01*
X1662936Y98177D01*
X1662419Y97411D01*
X1662058Y97066D01*
X1661541Y96836D01*
X1661076Y96759D01*
Y98369D01*
G01X1670087Y127661D02*
X1669320D01*
Y126731D01*
X1669550Y126421D01*
X1669819Y126214D01*
X1670202Y126111D01*
X1670585Y126214D01*
X1670854Y126421D01*
X1671084Y126731D01*
X1671237Y127093D01*
X1671314Y127506D01*
Y127868D01*
X1671237Y128178D01*
X1671084Y128539D01*
X1670854Y128849D01*
X1670624Y129056D01*
X1670317Y129211D01*
X1670049D01*
X1669742Y129108D01*
X1669512Y128901D01*
G01X1668060Y126576D02*
X1667830Y126318D01*
X1667562Y126163D01*
X1667217Y126111D01*
X1666872Y126214D01*
X1666604Y126421D01*
X1666412Y126783D01*
X1666374Y127196D01*
X1666450Y127609D01*
X1666642Y127868D01*
X1666910Y128074D01*
X1667179Y128126D01*
X1667447Y128074D01*
X1667792Y127868D01*
X1667677Y129211D01*
X1666642D01*
G01X1675087Y168194D02*
X1674320D01*
Y167264D01*
X1674550Y166954D01*
X1674819Y166747D01*
X1675202Y166644D01*
X1675585Y166747D01*
X1675854Y166954D01*
X1676084Y167264D01*
X1676237Y167626D01*
X1676314Y168039D01*
Y168401D01*
X1676237Y168711D01*
X1676084Y169072D01*
X1675854Y169382D01*
X1675624Y169589D01*
X1675317Y169744D01*
X1675049D01*
X1674742Y169641D01*
X1674512Y169434D01*
G01X1671757Y166644D02*
Y169744D01*
X1673175Y167522D01*
X1671259D01*
M02*
